G04 ================== begin FILE IDENTIFICATION RECORD ==================*
G04 Layout Name:  14545-sa.brd*
G04 Film Name:    DIF_REF_TOP*
G04 File Format:  Gerber RS274X*
G04 File Origin:  Cadence Allegro 16.5-S056*
G04 Origin Date:  Fri Aug 01 17:59:09 2014*
G04 *
G04 Layer:  BOARD GEOMETRY/OUTLINE*
G04 Layer:  BOARD GEOMETRY/DIF_REF_TOP*
G04 Layer:  BOARD GEOMETRY/PANEL_OUTLINE*
G04 *
G04 Offset:    (0.00 0.00)*
G04 Mirror:    No*
G04 Mode:      Positive*
G04 Rotation:  0*
G04 FullContactRelief:  No*
G04 UndefLineWidth:     6.00*
G04 ================== end FILE IDENTIFICATION RECORD ====================*
%FSLAX35Y35*MOIN*%
%IR0*IPPOS*OFA0.00000B0.00000*MIA0B0*SFA1.00000B1.00000*%
%ADD10C,.006*%
%ADD11C,.00375*%
G75*
%LPD*%
G75*
G54D10*
G01X-78741Y15000D02*
G03X-63741Y0I15000J0D01*
G01X-78741Y15000D02*
Y120047D01*
G01X-63741Y135047D02*
G03X-78741Y120047I0J-15000D01*
G01Y298866D02*
G03X-63741Y283866I15000J0D01*
G01X-78741Y319646D02*
Y298866D01*
G01X-63741Y334646D02*
G03X-78741Y319646I0J-15000D01*
G01Y908315D02*
G03X-63741Y893315I15000J0D01*
G01X-78741Y908315D02*
Y1104299D01*
G01X-63741Y1119299D02*
G03X-78741Y1104299I0J-15000D01*
G01Y1283118D02*
G03X-63741Y1268118I15000J0D01*
G01X-78741Y1304285D02*
Y1283118D01*
G01X-63741Y1319285D02*
G03X-78741Y1304285I0J-15000D01*
G01Y1892953D02*
G03X-63741Y1877953I15000J0D01*
G01X-78741Y1892953D02*
Y1977126D01*
G01X-63741Y1992126D02*
G03X-78741Y1977126I0J-15000D01*
G01X19882Y1197835D02*
X1969D01*
X0Y1195866D01*
Y832480D01*
X1969Y830512D01*
X19882D01*
G02Y823031I0J-3740D01*
G01X1969D01*
X0Y821063D01*
Y423031D01*
X1969Y421063D01*
X19882D01*
G02Y413583I0J-3740D01*
G01X1969D01*
X0Y411614D01*
Y223031D01*
X1969Y221063D01*
X19882D01*
G02Y213583I0J-3740D01*
G01X1969D01*
X0Y211614D01*
Y3937D01*
G03X3937Y0I3937J0D01*
G01X1029528D01*
G03X1033465Y3937I0J3937D01*
G01Y1424882D01*
X1029528Y1428819D01*
X1024213D01*
G02X1019291Y1433740I-1J4921D01*
G01Y1607933D01*
X1015354Y1611870D01*
X989744D01*
G02Y1616083I0J2107D01*
G01X1015354D01*
X1019291Y1620020D01*
Y1676496D01*
G02X1024213Y1681417I4921J0D01*
G01X1029528D01*
X1033465Y1685354D01*
Y1988189D01*
G03X1029528Y1992126I-3937J0D01*
G01X3937D01*
G03X0Y1988189I0J-3937D01*
G01Y1816732D01*
X1969Y1814764D01*
X19882D01*
G02Y1807283I0J-3740D01*
G01X1969D01*
X0Y1805315D01*
Y1407283D01*
X1969Y1405315D01*
X19882D01*
G02Y1397835I0J-3740D01*
G01X1969D01*
X0Y1395866D01*
Y1207283D01*
X1969Y1205315D01*
X19882D01*
G02Y1197835I0J-3740D01*
G01Y1197834D02*
X1969D01*
X0Y1195865D01*
Y832479D01*
X1969Y830511D01*
X19882D01*
G02Y823030I0J-3741D01*
G01X1969D01*
X0Y821062D01*
Y423030D01*
X1969Y421062D01*
X19882D01*
G02Y413582I0J-3740D01*
G01X1969D01*
X0Y411613D01*
Y223030D01*
X1969Y221062D01*
X19882D01*
G02Y213582I0J-3740D01*
G01X1969D01*
X0Y211613D01*
Y3936D01*
G03X3937Y-1I3937J0D01*
G01X1029528D01*
G03X1033465Y3936I0J3937D01*
G01Y1424881D01*
X1029528Y1428818D01*
X1024213D01*
G02X1019291Y1433739I-1J4921D01*
G01Y1607932D01*
X1015354Y1611869D01*
X989744D01*
G02Y1616082I0J2107D01*
G01X1015354D01*
X1019291Y1620019D01*
Y1676495D01*
G02X1024213Y1681416I4921J0D01*
G01X1029528D01*
X1033465Y1685353D01*
Y1988188D01*
G03X1029528Y1992125I-3937J0D01*
G01X3937D01*
G03X0Y1988188I0J-3937D01*
G01Y1816731D01*
X1969Y1814763D01*
X19882D01*
G02Y1807282I0J-3741D01*
G01X1969D01*
X0Y1805314D01*
Y1407282D01*
X1969Y1405314D01*
X19882D01*
G02Y1397834I0J-3740D01*
G01X1969D01*
X0Y1395865D01*
Y1207282D01*
X1969Y1205314D01*
X19882D01*
G02Y1197834I0J-3740D01*
G01X-7875Y0D02*
X-63741D01*
G01X-7875Y41772D02*
Y104969D01*
G01Y17252D02*
Y0D01*
G01Y41772D02*
G03X-1I3937J-1D01*
G01Y17213D02*
G03X-7875I-3937J0D01*
G01Y41772D02*
G03X-1I3937J-1D01*
G01Y17213D02*
G03X-7875I-3937J0D01*
G01Y129516D02*
Y135047D01*
G01D02*
X-63741D01*
G01X-7875Y129516D02*
G03X-1I3937J0D01*
G01Y104958D02*
G03X-7875I-3937J0D01*
G01Y283866D02*
Y300383D01*
G01X-19814Y283866D02*
X-63741D01*
G01X-7875D02*
X-19814D01*
G01X-1Y300383D02*
G03X-7875I-3937J0D01*
G01Y331986D02*
Y324003D01*
G01Y331986D02*
Y334646D01*
G01D02*
X-63741D01*
G01X-7875Y324003D02*
G03X-1I3937J0D01*
G01X-7875Y905988D02*
Y893315D01*
G01D02*
X-63741D01*
G01X-7875Y1069005D02*
Y933234D01*
G01D02*
G03X-1I3937J0D01*
G01Y905988D02*
G03X-7875I-3937J0D01*
G01Y1108863D02*
Y1119299D01*
G01X-19126D02*
X-7875D01*
G01X-15749D02*
X-63741D01*
G01X-7875Y1106300D02*
Y1111425D01*
G01Y1106300D02*
Y1092625D01*
G01D02*
G03X-1I3937J0D01*
G01Y1069005D02*
G03X-7875I-3937J0D01*
G01X-17894Y1268118D02*
X-7875D01*
G01Y1278280D02*
Y1268118D01*
G01Y1280567D02*
Y1275992D01*
G01X-15749Y1268118D02*
X-63741D01*
G01X-7875Y1309889D02*
G03X-1I3937J0D01*
G01Y1280567D02*
G03X-7875I-3937J0D01*
G01Y1309889D02*
G03X-1I3937J0D01*
G01Y1280567D02*
G03X-7875I-3937J0D01*
G01Y1309889D02*
Y1319285D01*
G01D02*
X-63741D01*
G01X-7875Y1889223D02*
Y1877953D01*
G01D02*
X-63741D01*
G01X-7875Y1912843D02*
Y1962926D01*
G01Y1912843D02*
G03X-1I3937J0D01*
G01Y1889223D02*
G03X-7875I-3937J0D01*
G01Y1912843D02*
G03X-1I3937J0D01*
G01Y1889223D02*
G03X-7875I-3937J0D01*
G01X-1Y1962926D02*
G03X-7875I-3937J0D01*
G01X-1D02*
G03X-7875I-3937J0D01*
G01Y1986546D02*
Y1992126D01*
G01D02*
X-63741D01*
G01X-7875Y1986546D02*
G03X-1I3937J0D01*
G01X-7875D02*
G03X-1I3937J0D01*
G01X37330Y-70164D02*
Y-82164D01*
G01X35030Y-70164D02*
X39630D01*
G01X41630Y-82164D02*
Y-70164D01*
G01Y-75964D02*
X42130Y-74964D01*
X42630Y-74364D01*
X43430Y-74164D01*
X44030Y-74364D01*
X44730Y-75164D01*
X45030Y-76364D01*
Y-82164D01*
G01X49330Y-74164D02*
Y-82164D01*
G01Y-70964D02*
X49130Y-70764D01*
Y-70364D01*
X49330Y-70164D01*
X49530Y-70364D01*
Y-70764D01*
X49330Y-70964D01*
G01X53830Y-80764D02*
X54330Y-81564D01*
X55030Y-82164D01*
X55630D01*
X56230Y-81764D01*
X56630Y-81164D01*
X56830Y-80364D01*
X56730Y-79164D01*
X56330Y-78564D01*
X54530Y-77364D01*
X54130Y-75964D01*
X54330Y-74964D01*
X54730Y-74364D01*
X55330Y-74164D01*
X55930Y-74364D01*
X56530Y-74964D01*
G01X65930Y-85164D02*
X66630Y-85964D01*
X67430Y-86164D01*
X68130Y-85964D01*
X68730Y-84964D01*
X69130Y-83564D01*
Y-74164D01*
G01Y-75764D02*
X68730Y-74964D01*
X68130Y-74364D01*
X67430Y-74164D01*
X66630Y-74564D01*
X66130Y-75364D01*
X65730Y-76764D01*
X65530Y-78164D01*
X65630Y-79364D01*
X66030Y-80764D01*
X66630Y-81764D01*
X67430Y-82164D01*
X68030Y-81964D01*
X68730Y-81164D01*
X69130Y-80364D01*
G01X71830Y-76764D02*
X75030D01*
X74730Y-75364D01*
X74230Y-74564D01*
X73530Y-74164D01*
X72830Y-74364D01*
X72230Y-74964D01*
X71830Y-76364D01*
X71630Y-77564D01*
Y-78764D01*
X71830Y-79964D01*
X72330Y-81164D01*
X72930Y-81964D01*
X73630Y-82164D01*
X74330Y-81764D01*
X75030Y-80564D01*
G01X77930Y-82164D02*
Y-74164D01*
G01Y-75764D02*
X78430Y-74964D01*
X78930Y-74364D01*
X79630Y-74164D01*
X80130Y-74364D01*
X80730Y-74964D01*
G01X83530Y-82164D02*
Y-70164D01*
G01Y-76164D02*
X84030Y-74964D01*
X84630Y-74364D01*
X85230Y-74164D01*
X86130Y-74564D01*
X86730Y-75364D01*
X87130Y-76764D01*
Y-78364D01*
X86930Y-79964D01*
X86530Y-81164D01*
X85830Y-81964D01*
X85230Y-82164D01*
X84630Y-81964D01*
X84030Y-81364D01*
X83530Y-80364D01*
G01X89830Y-76764D02*
X93030D01*
X92730Y-75364D01*
X92230Y-74564D01*
X91530Y-74164D01*
X90830Y-74364D01*
X90230Y-74964D01*
X89830Y-76364D01*
X89630Y-77564D01*
Y-78764D01*
X89830Y-79964D01*
X90330Y-81164D01*
X90930Y-81964D01*
X91630Y-82164D01*
X92330Y-81764D01*
X93030Y-80564D01*
G01X95930Y-82164D02*
Y-74164D01*
G01Y-75764D02*
X96430Y-74964D01*
X96930Y-74364D01*
X97630Y-74164D01*
X98130Y-74364D01*
X98730Y-74964D01*
G01X109330Y-74164D02*
Y-82164D01*
G01Y-70964D02*
X109130Y-70764D01*
Y-70364D01*
X109330Y-70164D01*
X109530Y-70364D01*
Y-70764D01*
X109330Y-70964D01*
G01X113830Y-80764D02*
X114330Y-81564D01*
X115030Y-82164D01*
X115630D01*
X116230Y-81764D01*
X116630Y-81164D01*
X116830Y-80364D01*
X116730Y-79164D01*
X116330Y-78564D01*
X114530Y-77364D01*
X114130Y-75964D01*
X114330Y-74964D01*
X114730Y-74364D01*
X115330Y-74164D01*
X115930Y-74364D01*
X116530Y-74964D01*
G01X125730Y-85164D02*
X126430Y-85964D01*
X127030Y-86164D01*
X127830Y-85764D01*
X128430Y-84764D01*
X128730Y-82964D01*
Y-74164D01*
G01Y-70964D02*
X128530Y-70764D01*
Y-70364D01*
X128730Y-70164D01*
X128930Y-70364D01*
Y-70764D01*
X128730Y-70964D01*
G01X131630Y-74164D02*
Y-79764D01*
X132030Y-81164D01*
X132630Y-81964D01*
X133330Y-82164D01*
X134030Y-81964D01*
X134630Y-81164D01*
X135030Y-79764D01*
G01Y-82164D02*
Y-74164D01*
G01X137830Y-80764D02*
X138330Y-81564D01*
X139030Y-82164D01*
X139630D01*
X140230Y-81764D01*
X140630Y-81164D01*
X140830Y-80364D01*
X140730Y-79164D01*
X140330Y-78564D01*
X138530Y-77364D01*
X138130Y-75964D01*
X138330Y-74964D01*
X138730Y-74364D01*
X139330Y-74164D01*
X139930Y-74364D01*
X140530Y-74964D01*
G01X145330Y-70164D02*
Y-82164D01*
G01X143930Y-74164D02*
X146730D01*
G01X156730Y-82164D02*
Y-71964D01*
X156930Y-70964D01*
X157330Y-70364D01*
X157930Y-70164D01*
X158530Y-70564D01*
X158830Y-71564D01*
G01X157630Y-74964D02*
X155630D01*
G01X163330Y-82164D02*
X162730Y-81964D01*
X162130Y-81164D01*
X161730Y-79764D01*
X161530Y-78164D01*
X161730Y-76564D01*
X162130Y-75164D01*
X162730Y-74364D01*
X163330Y-74164D01*
X163930Y-74364D01*
X164530Y-75164D01*
X164930Y-76564D01*
X165030Y-78164D01*
X164930Y-79764D01*
X164530Y-81164D01*
X163930Y-81964D01*
X163330Y-82164D01*
G01X167930D02*
Y-74164D01*
G01Y-75764D02*
X168430Y-74964D01*
X168930Y-74364D01*
X169630Y-74164D01*
X170130Y-74364D01*
X170730Y-74964D01*
G01X179230Y-85764D02*
X179830Y-86164D01*
X180630Y-85764D01*
X181130Y-84964D01*
X181530Y-83964D01*
X182130Y-80764D01*
X183430Y-74164D01*
G01X180230D02*
X182130Y-80764D01*
G01X187330Y-82164D02*
X186730Y-81964D01*
X186130Y-81164D01*
X185730Y-79764D01*
X185530Y-78164D01*
X185730Y-76564D01*
X186130Y-75164D01*
X186730Y-74364D01*
X187330Y-74164D01*
X187930Y-74364D01*
X188530Y-75164D01*
X188930Y-76564D01*
X189030Y-78164D01*
X188930Y-79764D01*
X188530Y-81164D01*
X187930Y-81964D01*
X187330Y-82164D01*
G01X191630Y-74164D02*
Y-79764D01*
X192030Y-81164D01*
X192630Y-81964D01*
X193330Y-82164D01*
X194030Y-81964D01*
X194630Y-81164D01*
X195030Y-79764D01*
G01Y-82164D02*
Y-74164D01*
G01X203930Y-82164D02*
Y-74164D01*
G01Y-75764D02*
X204430Y-74964D01*
X204930Y-74364D01*
X205630Y-74164D01*
X206130Y-74364D01*
X206730Y-74964D01*
G01X209830Y-76764D02*
X213030D01*
X212730Y-75364D01*
X212230Y-74564D01*
X211530Y-74164D01*
X210830Y-74364D01*
X210230Y-74964D01*
X209830Y-76364D01*
X209630Y-77564D01*
Y-78764D01*
X209830Y-79964D01*
X210330Y-81164D01*
X210930Y-81964D01*
X211630Y-82164D01*
X212330Y-81764D01*
X213030Y-80564D01*
G01X216730Y-82164D02*
Y-71964D01*
X216930Y-70964D01*
X217330Y-70364D01*
X217930Y-70164D01*
X218530Y-70564D01*
X218830Y-71564D01*
G01X217630Y-74964D02*
X215630D01*
G01X221830Y-76764D02*
X225030D01*
X224730Y-75364D01*
X224230Y-74564D01*
X223530Y-74164D01*
X222830Y-74364D01*
X222230Y-74964D01*
X221830Y-76364D01*
X221630Y-77564D01*
Y-78764D01*
X221830Y-79964D01*
X222330Y-81164D01*
X222930Y-81964D01*
X223630Y-82164D01*
X224330Y-81764D01*
X225030Y-80564D01*
G01X227930Y-82164D02*
Y-74164D01*
G01Y-75764D02*
X228430Y-74964D01*
X228930Y-74364D01*
X229630Y-74164D01*
X230130Y-74364D01*
X230730Y-74964D01*
G01X233830Y-76764D02*
X237030D01*
X236730Y-75364D01*
X236230Y-74564D01*
X235530Y-74164D01*
X234830Y-74364D01*
X234230Y-74964D01*
X233830Y-76364D01*
X233630Y-77564D01*
Y-78764D01*
X233830Y-79964D01*
X234330Y-81164D01*
X234930Y-81964D01*
X235630Y-82164D01*
X236330Y-81764D01*
X237030Y-80564D01*
G01X239630Y-82164D02*
Y-74164D01*
G01Y-76164D02*
X240030Y-75164D01*
X240630Y-74364D01*
X241430Y-74164D01*
X242130Y-74364D01*
X242730Y-75164D01*
X243030Y-76564D01*
Y-82164D01*
G01X248930Y-75164D02*
X248230Y-74364D01*
X247630Y-74164D01*
X246830Y-74564D01*
X246230Y-75364D01*
X245830Y-76764D01*
X245730Y-78164D01*
X245830Y-79564D01*
X246230Y-80764D01*
X246830Y-81764D01*
X247630Y-82164D01*
X248330Y-81764D01*
X248930Y-80964D01*
G01X251830Y-76764D02*
X255030D01*
X254730Y-75364D01*
X254230Y-74564D01*
X253530Y-74164D01*
X252830Y-74364D01*
X252230Y-74964D01*
X251830Y-76364D01*
X251630Y-77564D01*
Y-78764D01*
X251830Y-79964D01*
X252330Y-81164D01*
X252930Y-81964D01*
X253630Y-82164D01*
X254330Y-81764D01*
X255030Y-80564D01*
G01X265330Y-70164D02*
Y-82164D01*
G01X263930Y-74164D02*
X266730D01*
G01X271330Y-82164D02*
X270730Y-81964D01*
X270130Y-81164D01*
X269730Y-79764D01*
X269530Y-78164D01*
X269730Y-76564D01*
X270130Y-75164D01*
X270730Y-74364D01*
X271330Y-74164D01*
X271930Y-74364D01*
X272530Y-75164D01*
X272930Y-76564D01*
X273030Y-78164D01*
X272930Y-79764D01*
X272530Y-81164D01*
X271930Y-81964D01*
X271330Y-82164D01*
G01X282730D02*
Y-71964D01*
X282930Y-70964D01*
X283330Y-70364D01*
X283930Y-70164D01*
X284530Y-70564D01*
X284830Y-71564D01*
G01X283630Y-74964D02*
X281630D01*
G01X289330Y-74164D02*
Y-82164D01*
G01Y-70964D02*
X289130Y-70764D01*
Y-70364D01*
X289330Y-70164D01*
X289530Y-70364D01*
Y-70764D01*
X289330Y-70964D01*
G01X293630Y-82164D02*
Y-74164D01*
G01Y-76164D02*
X294030Y-75164D01*
X294630Y-74364D01*
X295430Y-74164D01*
X296130Y-74364D01*
X296730Y-75164D01*
X297030Y-76564D01*
Y-82164D01*
G01X303130Y-70164D02*
Y-82164D01*
G01Y-80364D02*
X302730Y-81364D01*
X302130Y-81964D01*
X301430Y-82164D01*
X300630Y-81764D01*
X300030Y-80764D01*
X299630Y-79564D01*
X299530Y-78164D01*
X299630Y-76764D01*
X300030Y-75564D01*
X300630Y-74564D01*
X301430Y-74164D01*
X302130Y-74364D01*
X302630Y-74764D01*
X303130Y-75564D01*
G01X313330Y-70164D02*
Y-82164D01*
G01X311930Y-74164D02*
X314730D01*
G01X317630Y-82164D02*
Y-70164D01*
G01Y-75964D02*
X318130Y-74964D01*
X318630Y-74364D01*
X319430Y-74164D01*
X320030Y-74364D01*
X320730Y-75164D01*
X321030Y-76364D01*
Y-82164D01*
G01X323830Y-76764D02*
X327030D01*
X326730Y-75364D01*
X326230Y-74564D01*
X325530Y-74164D01*
X324830Y-74364D01*
X324230Y-74964D01*
X323830Y-76364D01*
X323630Y-77564D01*
Y-78764D01*
X323830Y-79964D01*
X324330Y-81164D01*
X324930Y-81964D01*
X325630Y-82164D01*
X326330Y-81764D01*
X327030Y-80564D01*
G01X339130Y-70164D02*
Y-82164D01*
G01Y-80364D02*
X338730Y-81364D01*
X338130Y-81964D01*
X337430Y-82164D01*
X336630Y-81764D01*
X336030Y-80764D01*
X335630Y-79564D01*
X335530Y-78164D01*
X335630Y-76764D01*
X336030Y-75564D01*
X336630Y-74564D01*
X337430Y-74164D01*
X338130Y-74364D01*
X338630Y-74764D01*
X339130Y-75564D01*
G01X343330Y-74164D02*
Y-82164D01*
G01Y-70964D02*
X343130Y-70764D01*
Y-70364D01*
X343330Y-70164D01*
X343530Y-70364D01*
Y-70764D01*
X343330Y-70964D01*
G01X348730Y-82164D02*
Y-71964D01*
X348930Y-70964D01*
X349330Y-70364D01*
X349930Y-70164D01*
X350530Y-70564D01*
X350830Y-71564D01*
G01X349630Y-74964D02*
X347630D01*
G01X354730Y-82164D02*
Y-71964D01*
X354930Y-70964D01*
X355330Y-70364D01*
X355930Y-70164D01*
X356530Y-70564D01*
X356830Y-71564D01*
G01X355630Y-74964D02*
X353630D01*
G01X359830Y-76764D02*
X363030D01*
X362730Y-75364D01*
X362230Y-74564D01*
X361530Y-74164D01*
X360830Y-74364D01*
X360230Y-74964D01*
X359830Y-76364D01*
X359630Y-77564D01*
Y-78764D01*
X359830Y-79964D01*
X360330Y-81164D01*
X360930Y-81964D01*
X361630Y-82164D01*
X362330Y-81764D01*
X363030Y-80564D01*
G01X365930Y-82164D02*
Y-74164D01*
G01Y-75764D02*
X366430Y-74964D01*
X366930Y-74364D01*
X367630Y-74164D01*
X368130Y-74364D01*
X368730Y-74964D01*
G01X371830Y-76764D02*
X375030D01*
X374730Y-75364D01*
X374230Y-74564D01*
X373530Y-74164D01*
X372830Y-74364D01*
X372230Y-74964D01*
X371830Y-76364D01*
X371630Y-77564D01*
Y-78764D01*
X371830Y-79964D01*
X372330Y-81164D01*
X372930Y-81964D01*
X373630Y-82164D01*
X374330Y-81764D01*
X375030Y-80564D01*
G01X377630Y-82164D02*
Y-74164D01*
G01Y-76164D02*
X378030Y-75164D01*
X378630Y-74364D01*
X379430Y-74164D01*
X380130Y-74364D01*
X380730Y-75164D01*
X381030Y-76564D01*
Y-82164D01*
G01X385330Y-70164D02*
Y-82164D01*
G01X383930Y-74164D02*
X386730D01*
G01X391330D02*
Y-82164D01*
G01Y-70964D02*
X391130Y-70764D01*
Y-70364D01*
X391330Y-70164D01*
X391530Y-70364D01*
Y-70764D01*
X391330Y-70964D01*
G01X399130Y-82164D02*
Y-74164D01*
G01Y-75564D02*
X398730Y-74764D01*
X398130Y-74364D01*
X397430Y-74164D01*
X396730Y-74564D01*
X396130Y-75364D01*
X395730Y-76564D01*
X395530Y-78164D01*
X395730Y-79764D01*
X396130Y-80964D01*
X396730Y-81764D01*
X397430Y-82164D01*
X398130Y-81964D01*
X398730Y-81364D01*
X399130Y-80564D01*
G01X403330Y-82164D02*
Y-70164D01*
G01X415330D02*
Y-82164D01*
G01X413930Y-74164D02*
X416730D01*
G01X419930Y-82164D02*
Y-74164D01*
G01Y-75764D02*
X420430Y-74964D01*
X420930Y-74364D01*
X421630Y-74164D01*
X422130Y-74364D01*
X422730Y-74964D01*
G01X429130Y-82164D02*
Y-74164D01*
G01Y-75564D02*
X428730Y-74764D01*
X428130Y-74364D01*
X427430Y-74164D01*
X426730Y-74564D01*
X426130Y-75364D01*
X425730Y-76564D01*
X425530Y-78164D01*
X425730Y-79764D01*
X426130Y-80964D01*
X426730Y-81764D01*
X427430Y-82164D01*
X428130Y-81964D01*
X428730Y-81364D01*
X429130Y-80564D01*
G01X434930Y-75164D02*
X434230Y-74364D01*
X433630Y-74164D01*
X432830Y-74564D01*
X432230Y-75364D01*
X431830Y-76764D01*
X431730Y-78164D01*
X431830Y-79564D01*
X432230Y-80764D01*
X432830Y-81764D01*
X433630Y-82164D01*
X434330Y-81764D01*
X434930Y-80964D01*
G01X437830Y-76764D02*
X441030D01*
X440730Y-75364D01*
X440230Y-74564D01*
X439530Y-74164D01*
X438830Y-74364D01*
X438230Y-74964D01*
X437830Y-76364D01*
X437630Y-77564D01*
Y-78764D01*
X437830Y-79964D01*
X438330Y-81164D01*
X438930Y-81964D01*
X439630Y-82164D01*
X440330Y-81764D01*
X441030Y-80564D01*
G01X443830Y-80764D02*
X444330Y-81564D01*
X445030Y-82164D01*
X445630D01*
X446230Y-81764D01*
X446630Y-81164D01*
X446830Y-80364D01*
X446730Y-79164D01*
X446330Y-78564D01*
X444530Y-77364D01*
X444130Y-75964D01*
X444330Y-74964D01*
X444730Y-74364D01*
X445330Y-74164D01*
X445930Y-74364D01*
X446530Y-74964D01*
G01X457330Y-74164D02*
Y-82164D01*
G01Y-70964D02*
X457130Y-70764D01*
Y-70364D01*
X457330Y-70164D01*
X457530Y-70364D01*
Y-70764D01*
X457330Y-70964D01*
G01X461630Y-82164D02*
Y-74164D01*
G01Y-76164D02*
X462030Y-75164D01*
X462630Y-74364D01*
X463430Y-74164D01*
X464130Y-74364D01*
X464730Y-75164D01*
X465030Y-76564D01*
Y-82164D01*
G01X475330D02*
Y-70164D01*
G01X483130Y-82164D02*
Y-74164D01*
G01Y-75564D02*
X482730Y-74764D01*
X482130Y-74364D01*
X481430Y-74164D01*
X480730Y-74564D01*
X480130Y-75364D01*
X479730Y-76564D01*
X479530Y-78164D01*
X479730Y-79764D01*
X480130Y-80964D01*
X480730Y-81764D01*
X481430Y-82164D01*
X482130Y-81964D01*
X482730Y-81364D01*
X483130Y-80564D01*
G01X485230Y-85764D02*
X485830Y-86164D01*
X486630Y-85764D01*
X487130Y-84964D01*
X487530Y-83964D01*
X488130Y-80764D01*
X489430Y-74164D01*
G01X486230D02*
X488130Y-80764D01*
G01X491830Y-76764D02*
X495030D01*
X494730Y-75364D01*
X494230Y-74564D01*
X493530Y-74164D01*
X492830Y-74364D01*
X492230Y-74964D01*
X491830Y-76364D01*
X491630Y-77564D01*
Y-78764D01*
X491830Y-79964D01*
X492330Y-81164D01*
X492930Y-81964D01*
X493630Y-82164D01*
X494330Y-81764D01*
X495030Y-80564D01*
G01X497930Y-82164D02*
Y-74164D01*
G01Y-75764D02*
X498430Y-74964D01*
X498930Y-74364D01*
X499630Y-74164D01*
X500130Y-74364D01*
X500730Y-74964D01*
G01X511330Y-70164D02*
Y-82164D01*
G01X509030Y-70164D02*
X513630D01*
G01X517330Y-82164D02*
X516530Y-81964D01*
X515830Y-81164D01*
X515230Y-79964D01*
X514830Y-78564D01*
X514630Y-76964D01*
Y-75364D01*
X514830Y-73764D01*
X515230Y-72364D01*
X515830Y-71164D01*
X516530Y-70364D01*
X517330Y-70164D01*
X518130Y-70364D01*
X518830Y-71164D01*
X519430Y-72364D01*
X519830Y-73764D01*
X520030Y-75364D01*
Y-76964D01*
X519830Y-78564D01*
X519430Y-79964D01*
X518830Y-81164D01*
X518130Y-81964D01*
X517330Y-82164D01*
G01X521330D02*
Y-70164D01*
X523730D01*
X524530Y-70764D01*
X525130Y-72164D01*
X525330Y-73764D01*
X525130Y-75364D01*
X524630Y-76564D01*
X523730Y-77164D01*
X521330D01*
G01X1041337Y24677D02*
Y0D01*
G01Y217343D02*
Y48297D01*
G01Y0D02*
X1097204D01*
G01X1033463Y48297D02*
G03X1041337I3937J0D01*
G01Y24677D02*
G03X1033463I-3937J0D01*
G01Y48297D02*
G03X1041337I3937J0D01*
G01Y24677D02*
G03X1033463I-3937J0D01*
G01X1041337Y217343D02*
G03X1033463I-3937J0D01*
G01X1041337D02*
G03X1033463I-3937J0D01*
G01X1041337Y445039D02*
Y240963D01*
G01X1033463D02*
G03X1041337I3937J0D01*
G01X1033463D02*
G03X1041337I3937J0D01*
G01Y697474D02*
Y468601D01*
G01X1033463Y468659D02*
G03X1041337I3937J0D01*
G01Y445039D02*
G03X1033463I-3937J0D01*
G01Y468659D02*
G03X1041337I3937J0D01*
G01Y445039D02*
G03X1033463I-3937J0D01*
G01X1041337Y996851D02*
Y721093D01*
G01X1033463D02*
G03X1041337I3937J0D01*
G01Y697474D02*
G03X1033463I-3937J-1D01*
G01Y721093D02*
G03X1041337I3937J0D01*
G01Y697474D02*
G03X1033463I-3937J-1D01*
G01X1041337Y1344059D02*
Y1020472D01*
G01X1033463D02*
G03X1041337I3937J0D01*
G01Y996851D02*
G03X1033463I-3937J1D01*
G01Y1020472D02*
G03X1041337I3937J0D01*
G01Y996851D02*
G03X1033463I-3937J1D01*
G01X1041337Y1367679D02*
Y1393701D01*
G01X1033463Y1367679D02*
G03X1041337I3937J0D01*
G01Y1344059D02*
G03X1033463I-3937J0D01*
G01Y1367679D02*
G03X1041337I3937J0D01*
G01Y1344059D02*
G03X1033463I-3937J0D01*
G01X1041337Y1393701D02*
X1097204D01*
G01X1041337Y1733129D02*
Y1716535D01*
G01X1065042D02*
X1041337D01*
G01X1056337D02*
X1097204D01*
G01X1041337Y1739719D02*
Y1731535D01*
G01Y1959242D02*
Y1763311D01*
G01X1033463Y1763339D02*
G03X1041337I3937J0D01*
G01Y1739719D02*
G03X1033463I-3937J0D01*
G01Y1763339D02*
G03X1041337I3937J0D01*
G01Y1739719D02*
G03X1033463I-3937J0D01*
G01X1041337Y1959242D02*
G03X1033463I-3937J0D01*
G01X1041337D02*
G03X1033463I-3937J0D01*
G01X1041337Y1992126D02*
X1097204D01*
G01X1041337Y1982862D02*
Y1992126D01*
G01X1033463Y1982862D02*
G03X1041337I3937J0D01*
G01X1033463D02*
G03X1041337I3937J0D01*
G01X1112204Y648419D02*
Y15000D01*
G01X1097204Y0D02*
G03X1112204Y15000I0J15000D01*
G01Y656293D02*
G03Y648419I0J-3937D01*
G01Y1378701D02*
Y656293D01*
G01Y1378701D02*
G03X1097204Y1393701I-15000J0D01*
G01Y1716535D02*
G03X1112204Y1731535I0J15000D01*
G01Y1977126D02*
Y1731535D01*
G01Y1977126D02*
G03X1097204Y1992126I-15000J0D01*
G54D11*
G01X85630Y146141D02*
X90768D01*
G01D02*
G02X91094Y146006I0J-461D01*
G01D02*
G02X91229Y145680I-326J-326D01*
G01D02*
Y144678D01*
G01D02*
G03X91527Y144291I400J0D01*
G01D02*
G03X91629Y144278I101J387D01*
G01D02*
X98885D01*
G01X85630Y141141D02*
X90800D01*
G01D02*
X90839Y141156D01*
G01D02*
G03X91017Y141260I-204J553D01*
G01D02*
X91096Y141328D01*
G01D02*
G03X91229Y141614I-241J286D01*
G01D02*
Y142578D01*
G01D02*
G02X91498Y142956I400J0D01*
G01D02*
G02X91629Y142978I131J-379D01*
G01D02*
X97302D01*
G01X77166Y120511D02*
X79445D01*
G01D02*
X79458Y120498D01*
G01D02*
G02X81221Y119857I0J-2745D01*
G01D02*
G03X81615Y119694I394J394D01*
G01D02*
X95899D01*
G01X77166Y117362D02*
X79094D01*
G01D02*
X79107Y117349D01*
G01D02*
G03X80799Y118050I0J2393D01*
G01D02*
G02X81629Y118394I830J-830D01*
G01D02*
X95899D01*
G01X77166Y126811D02*
X79094D01*
G01D02*
X79107Y126798D01*
G01D02*
G03X80799Y127499I0J2393D01*
G01D02*
G02X81629Y127843I830J-830D01*
G01D02*
X84499D01*
G01D02*
G02X86218Y127131I0J-2431D01*
G01D02*
X86599Y126750D01*
G01X77166Y129960D02*
X79445D01*
G01D02*
X79458Y129947D01*
G01D02*
G02X81221Y129306I0J-2745D01*
G01D02*
G03X81615Y129143I394J394D01*
G01D02*
X85499D01*
G01D02*
G03X86899Y130543I0J1400D01*
G01D02*
Y130567D01*
G01X85630Y156141D02*
X90396D01*
G01D02*
G03X90985Y156385I0J833D01*
G01D02*
X91095Y156495D01*
G01D02*
G03X91229Y156819I-325J324D01*
G01D02*
Y157578D01*
G01D02*
G02X91499Y157956I400J0D01*
G01D02*
G02X91508Y157959I131J-378D01*
G01D02*
G02X91629Y157978I122J-381D01*
G01D02*
X99500D01*
G01X85630Y161141D02*
X90597D01*
G01D02*
G02X91044Y160956I0J-633D01*
G01D02*
G02X91229Y160509I-448J-447D01*
G01D02*
Y159678D01*
G01D02*
G03X91506Y159297I401J0D01*
G01D02*
G03X91510Y159295I179J353D01*
G01D02*
G03X91629Y159278I116J384D01*
G01D02*
X99500D01*
G01X26299Y387629D02*
X25785Y387115D01*
G01D02*
G02X24751Y386527I-1586J1586D01*
G01D02*
G02X24512Y386479I-561J2172D01*
G01D02*
G02X24451Y386472I-286J2224D01*
G01D02*
G02X24199Y386458I-250J2229D01*
G01D02*
X22109D01*
G01D02*
G02X22102I-4J1782D01*
G01D02*
G02X22046Y386459I4J1782D01*
G01D02*
G02X21586Y386536I62J1781D01*
G01D02*
G02X21513Y386558I478J1717D01*
G01D02*
G02X21510Y386560I954J1434D01*
G01D02*
G02X21280Y386660I594J1681D01*
G01D02*
G02X20849Y386980I835J1575D01*
G01D02*
G03X18881Y387795I-1968J-1968D01*
G01D02*
X12575D01*
G01D02*
X12569Y387789D01*
G01X26299Y383854D02*
X25203Y384949D01*
G01D02*
G03X24700Y385158I-504J-503D01*
G01D02*
X21381D01*
G01D02*
G03X21000Y385000I0J-539D01*
G01D02*
G03X20774Y384584I589J-589D01*
G01D02*
Y384563D01*
G01D02*
G02X20490Y384014I-673J0D01*
G01D02*
G02X20099Y383852I-391J391D01*
G01D02*
X12569D01*
G01X26799Y458497D02*
X26073Y457771D01*
G01D02*
G02X24999Y457326I-1074J1074D01*
G01D02*
X21664D01*
G01D02*
G02X20476Y457818I0J1680D01*
G01D02*
G03X18436Y458663I-2040J-2040D01*
G01D02*
X18430Y458657D01*
G01D02*
X12569D01*
G01X26899Y454850D02*
G03X25723Y456026I-1176J0D01*
G01D02*
X21620D01*
G01D02*
G03X20493Y455559I0J-1594D01*
G01D02*
G02X18482Y454726I-2011J2011D01*
G01D02*
X18476Y454720D01*
G01D02*
X12569D01*
G01X26599Y442749D02*
G02X24999Y441578I-1600J508D01*
G01D02*
X22271D01*
G01D02*
X22270Y441577D01*
G01D02*
G02X22223I-23J1985D01*
G01D02*
G02X21770Y441641I49J1985D01*
G01D02*
G02X21657Y441675I515J1917D01*
G01D02*
G02X21494Y441735I603J1891D01*
G01D02*
G02X21415Y441770I764J1832D01*
G01D02*
G02X20868Y442159I860J1789D01*
G01D02*
G03X19043Y442915I-1825J-1825D01*
G01D02*
X19037Y442909D01*
G01D02*
X12569D01*
G01X26492Y439350D02*
G03X24999Y440278I-1493J-737D01*
G01D02*
X22191D01*
G01D02*
G03X21397Y440221I-2J-5524D01*
G01D02*
G03X20452Y439579I0J-1017D01*
G01D02*
G02X19777Y439082I-750J312D01*
G01D02*
G02X19024Y438978I-755J2689D01*
G01D02*
X19018Y438972D01*
G01D02*
X12569D01*
G01X26299Y403376D02*
G02X25709Y402333I-1217J0D01*
G01D02*
G02X25402Y402206I-307J307D01*
G01D02*
X21839D01*
G01D02*
G02X20451Y402781I0J1963D01*
G01D02*
G03X18611Y403543I-1840J-1840D01*
G01D02*
X18605Y403537D01*
G01D02*
X12569D01*
G01X26299Y399601D02*
Y400009D01*
G01D02*
G03X25402Y400906I-897J0D01*
G01D02*
X22096D01*
G01D02*
G03X20842Y400386I1J-1774D01*
G01D02*
X20841D01*
G01D02*
G02X18958Y399606I-1883J1883D01*
G01D02*
X12575D01*
G01D02*
X12569Y399600D01*
G01X64397Y474446D02*
G02X61085Y473074I-3312J3312D01*
G01D02*
X22715D01*
G01D02*
G02X20965Y473799I0J2475D01*
G01D02*
G03X19488Y474411I-1477J-1477D01*
G01D02*
X19482Y474405D01*
G01D02*
X12569D01*
G01X64403Y471046D02*
G03X62645Y471774I-1758J-1758D01*
G01D02*
X22133D01*
G01D02*
G03X21172Y471376I0J-1359D01*
G01D02*
X20872Y471076D01*
G01D02*
G02X19419Y470474I-1453J1453D01*
G01D02*
X19413Y470468D01*
G01D02*
X12569D01*
G01X26524Y426720D02*
G02X24854Y425050I-1670J0D01*
G01D02*
X22000D01*
G01D02*
G02X21118Y425350I-1J1444D01*
G01D02*
G02X20883Y425917I567J567D01*
G01D02*
Y425955D01*
G01D02*
G03X20583Y426417I-1235J-474D01*
G01D02*
X20500Y426500D01*
G01D02*
G03X18904Y427161I-1596J-1596D01*
G01D02*
X12569D01*
G01X26399Y423322D02*
G03X25366Y423750I-1033J-1033D01*
G01D02*
X22294D01*
G01D02*
G03X22173Y423742I0J-922D01*
G01D02*
G03X21914Y423668I121J-914D01*
G01D02*
G03X21642Y423480I380J-840D01*
G01D02*
G02X21036Y423229I-606J606D01*
G01D02*
X12575D01*
G01D02*
X12569Y423223D01*
G01X36499Y521550D02*
G02X34499Y520318I-2000J1007D01*
G01D02*
X28336D01*
G01D02*
G02X27421Y520776I-14J1115D01*
G01D02*
G03X26506Y521233I-900J-658D01*
G01D02*
X25381D01*
G01D02*
G03X24466Y520776I-15J-1115D01*
G01D02*
G02X23551Y520318I-901J657D01*
G01D02*
X22142D01*
G01D02*
G02X21099Y520750I0J1475D01*
G01D02*
G03X18914Y521655I-2185J-2185D01*
G01D02*
X18908Y521649D01*
G01D02*
X12569D01*
G01X36499Y517775D02*
G03X34499Y519018I-2000J-988D01*
G01D02*
X22087D01*
G01D02*
G03X21913Y519005I6J-1256D01*
G01D02*
G03X21199Y518650I173J-1244D01*
G01D02*
G02X20931Y518410I-2297J2295D01*
G01D02*
G02X19260Y517718I-1671J1671D01*
G01D02*
X19254Y517712D01*
G01D02*
X12569D01*
G01X85630Y551653D02*
X90406D01*
G01D02*
G02X90988Y551412I0J-823D01*
G01D02*
X91098Y551302D01*
G01D02*
G02X91229Y550986I-316J-316D01*
G01D02*
Y550190D01*
G01D02*
G03X91497Y549812I401J0D01*
G01D02*
G03X91629Y549790I131J378D01*
G01D02*
X98277D01*
G01X85630Y546653D02*
X90695D01*
G01D02*
G03X90971Y546763I0J401D01*
G01D02*
X91097Y546882D01*
G01D02*
G03X91229Y547168I-244J286D01*
G01D02*
Y548090D01*
G01D02*
G02X91498Y548468I400J0D01*
G01D02*
G02X91629Y548490I131J-379D01*
G01D02*
X98276D01*
G01X77166Y526023D02*
X80166D01*
G01D02*
X80179Y526010D01*
G01D02*
G02X81702Y525554I1J-2769D01*
G01D02*
G03X82194Y525350I492J492D01*
G01D02*
X99655D01*
G01X77166Y522874D02*
X80905D01*
G01D02*
X80918Y522861D01*
G01D02*
G03X82099Y523350I0J1670D01*
G01D02*
G02X83475Y524029I1690J-1690D01*
G01D02*
G02X83789Y524050I316J-2369D01*
G01D02*
X97424D01*
G01X85630Y561653D02*
X90587D01*
G01D02*
G03X91041Y561841I0J642D01*
G01D02*
G03X91229Y562295I-454J454D01*
G01D02*
Y563090D01*
G01D02*
G02X91497Y563467I399J0D01*
G01D02*
G02X91500Y563468I128J-379D01*
G01D02*
G02X91629Y563490I131J-378D01*
G01D02*
X96523D01*
G01X59999Y537550D02*
Y536771D01*
G01D02*
G02X59102Y536016I-766J0D01*
G01D02*
Y536015D01*
G01D02*
G03X58517Y536066I-587J-3352D01*
G01D02*
X53570D01*
G01D02*
G02X52655Y536524I-14J1115D01*
G01D02*
G03X51740Y536981I-900J-658D01*
G01D02*
X50615D01*
G01D02*
G03X49700Y536524I-15J-1115D01*
G01D02*
G02X48785Y536066I-901J657D01*
G01D02*
X47660D01*
G01D02*
G02X46745Y536524I-14J1115D01*
G01D02*
G03X45830Y536981I-900J-658D01*
G01D02*
X44705D01*
G01D02*
G03X43790Y536524I-15J-1115D01*
G01D02*
G02X42875Y536066I-901J657D01*
G01D02*
X41750D01*
G01D02*
G02X40835Y536524I-14J1115D01*
G01D02*
G03X39920Y536981I-900J-658D01*
G01D02*
X38795D01*
G01D02*
G03X37880Y536524I-15J-1115D01*
G01D02*
G02X36965Y536066I-901J657D01*
G01D02*
X35840D01*
G01D02*
G02X34925Y536524I-14J1115D01*
G01D02*
G03X34010Y536981I-900J-658D01*
G01D02*
X32885D01*
G01D02*
G03X31970Y536524I-15J-1115D01*
G01D02*
G02X31055Y536066I-901J657D01*
G01D02*
X22369D01*
G01D02*
G02X21485Y536432I0J1250D01*
G01D02*
G03X19141Y537403I-2344J-2344D01*
G01D02*
X19135Y537397D01*
G01D02*
X12569D01*
G01X77166Y532323D02*
X80662D01*
G01D02*
X80675Y532310D01*
G01D02*
G03X81708Y532738I0J1461D01*
G01D02*
G02X82703Y533150I995J-995D01*
G01D02*
X84026D01*
G01D02*
G02X86199Y532250I0J-3073D01*
G01X60003Y534150D02*
G03X58516Y534766I-1487J-1487D01*
G01D02*
X23469D01*
G01D02*
G03X21499Y533950I0J-2786D01*
G01D02*
G02X20331Y533466I-1168J1168D01*
G01D02*
X12575D01*
G01D02*
X12569Y533460D01*
G01X77166Y535472D02*
X80360D01*
G01D02*
X80373Y535459D01*
G01D02*
G02X81677Y534919I0J-1844D01*
G01D02*
G03X82809Y534450I1132J1132D01*
G01D02*
X84111D01*
G01D02*
G03X84986Y534812I1J1237D01*
G01D02*
X86199Y536025D01*
G01X26399Y505741D02*
G02X25228Y504570I-1171J0D01*
G01D02*
X21706D01*
G01D02*
G02X21072Y504687I-1J1769D01*
G01D02*
G02X20455Y505088I635J1651D01*
G01D02*
G03X18478Y505907I-1977J-1977D01*
G01D02*
X18472Y505901D01*
G01D02*
X12569D01*
G01X26399Y501966D02*
G03X25095Y503270I-1304J0D01*
G01D02*
X21553D01*
G01D02*
G03X21320Y503250I0J-1369D01*
G01D02*
G03X20585Y502869I233J-1349D01*
G01D02*
G02X18415Y501970I-2170J2170D01*
G01D02*
X18409Y501964D01*
G01D02*
X12569D01*
G01X64700Y489700D02*
G02X62629Y488842I-2071J2071D01*
G01D02*
X22141D01*
G01D02*
G02X20980Y489323I0J1642D01*
G01D02*
G03X18962Y490159I-2018J-2018D01*
G01D02*
X18956Y490153D01*
G01D02*
X12569D01*
G01X64600Y486300D02*
G03X63358Y487542I-1242J0D01*
G01D02*
X21940D01*
G01D02*
G03X20711Y487033I0J-1738D01*
G01D02*
G02X18753Y486222I-1958J1958D01*
G01D02*
X18747Y486216D01*
G01D02*
X12569D01*
G01X26568Y639604D02*
X26304Y639340D01*
G01D02*
G02X24100Y638427I-2204J2204D01*
G01D02*
X21540D01*
G01D02*
G02X20446Y638880I0J1547D01*
G01D02*
G03X18309Y639765I-2137J-2137D01*
G01D02*
X18303Y639759D01*
G01D02*
X12569D01*
G01X26568Y635950D02*
X26304Y636214D01*
G01D02*
G03X24100Y637127I-2204J-2204D01*
G01D02*
X21512D01*
G01D02*
G03X20445Y636685I0J-1509D01*
G01D02*
G02X18376Y635828I-2069J2069D01*
G01D02*
X18370Y635822D01*
G01D02*
X12569D01*
G01X95629Y619571D02*
G02X92700Y626642I7071J7071D01*
G01D02*
Y730246D01*
G01X94000Y730245D02*
Y626642D01*
G01D02*
G03X96549Y620491I8699J1D01*
G01X98270Y608170D02*
X93130Y613310D01*
G01D02*
G02X90200Y620382I7070J7072D01*
G01D02*
Y731258D01*
G01X85630Y566653D02*
X90748D01*
G01D02*
G02X91088Y566512I0J-480D01*
G01D02*
G02X91229Y566172I-339J-340D01*
G01D02*
Y565190D01*
G01D02*
G03X91497Y564812I401J0D01*
G01D02*
G03X91571Y564794I131J378D01*
G01D02*
G03X91629Y564790I56J396D01*
G01D02*
X96522D01*
G01X95200Y609400D02*
X91829Y612770D01*
G01D02*
G02X88900Y619842I7071J7071D01*
G01D02*
Y660583D01*
G01X27499Y623857D02*
X27143Y623501D01*
G01D02*
G02X25161Y622680I-1983J1983D01*
G01D02*
X21519D01*
G01D02*
G02X20471Y623114I0J1482D01*
G01D02*
G03X18291Y624017I-2180J-2180D01*
G01D02*
X18285Y624011D01*
G01D02*
X12569D01*
G01X27499Y620203D02*
G03X24657Y621380I-2842J-2842D01*
G01D02*
X21481D01*
G01D02*
G03X20486Y620968I0J-1407D01*
G01D02*
G02X18342Y620080I-2144J2144D01*
G01D02*
X18336Y620074D01*
G01D02*
X12569D01*
G01X84700Y649207D02*
Y585232D01*
G01D02*
G02X81771Y578161I-10000J0D01*
G01D02*
X76729Y573119D01*
G01D02*
G02X72818Y571499I-3911J3911D01*
G01D02*
X21703D01*
G01D02*
G02X20527Y571986I0J1663D01*
G01D02*
G03X18475Y572836I-2052J-2052D01*
G01D02*
X18469Y572830D01*
G01D02*
X12569D01*
G01X86000Y649207D02*
Y585232D01*
G01D02*
G02X82691Y577241I-11300J-1D01*
G01D02*
X77649Y572199D01*
G01D02*
G02X72819Y570199I-4830J4832D01*
G01D02*
X21621D01*
G01D02*
G03X20877Y569891I0J-1052D01*
G01D02*
G02X18482Y568899I-2395J2395D01*
G01D02*
X18476Y568893D01*
G01D02*
X12569D01*
G01X26999Y656550D02*
Y655757D01*
G01D02*
G02X26499Y654550I-1707J0D01*
G01D02*
G02X25596Y654176I-903J903D01*
G01D02*
X21520D01*
G01D02*
G02X20470Y654611I0J1485D01*
G01D02*
G03X18292Y655513I-2178J-2178D01*
G01D02*
X18286Y655507D01*
G01D02*
X12569D01*
G01X26737Y651957D02*
G03X24518Y652876I-2219J-2219D01*
G01D02*
X21515D01*
G01D02*
G03X20441Y652431I0J-1519D01*
G01D02*
G02X18377Y651576I-2064J2064D01*
G01D02*
X18371Y651570D01*
G01D02*
X12569D01*
G01X27687Y671101D02*
X27579Y670992D01*
G01D02*
G02X24999Y669924I-2579J2580D01*
G01D02*
X22087D01*
G01D02*
G02X20725Y670488I0J1926D01*
G01D02*
X20271Y670941D01*
G01D02*
G03X19500Y671261I-772J-771D01*
G01D02*
X19494Y671255D01*
G01D02*
X12569D01*
G01X27687Y667447D02*
X27579Y667556D01*
G01D02*
G03X24999Y668624I-2579J-2580D01*
G01D02*
X21813D01*
G01D02*
G03X21028Y668484I1J-2278D01*
G01D02*
X21024Y668483D01*
G01D02*
G03X20196Y667954I789J-2148D01*
G01D02*
G02X18675Y667324I-1521J1521D01*
G01D02*
X18669Y667318D01*
G01D02*
X12569D01*
G01X88900Y660583D02*
G03X88442Y661498I-1115J14D01*
G01D02*
G02X87985Y662413I658J900D01*
G01D02*
Y663538D01*
G01D02*
G02X88442Y664453I1115J15D01*
G01D02*
G03X88900Y665368I-657J901D01*
G01D02*
Y666493D01*
G01D02*
G03X88442Y667408I-1115J14D01*
G01D02*
G02X87985Y668323I658J900D01*
G01D02*
Y669448D01*
G01D02*
G02X88442Y670363I1115J15D01*
G01D02*
G03X88900Y671278I-657J901D01*
G01D02*
Y672403D01*
G01D02*
G03X88442Y673318I-1115J14D01*
G01D02*
G02X87985Y674233I658J900D01*
G01D02*
Y675358D01*
G01D02*
G02X88442Y676273I1115J15D01*
G01D02*
G03X88900Y677188I-657J901D01*
G01D02*
Y694802D01*
G01D02*
G03X88442Y695717I-1115J14D01*
G01D02*
G02X87985Y696632I658J900D01*
G01D02*
Y697757D01*
G01D02*
G02X88442Y698672I1115J15D01*
G01D02*
G03X88900Y699587I-657J901D01*
G01D02*
Y700712D01*
G01D02*
G03X88442Y701627I-1115J14D01*
G01D02*
G02X87985Y702542I658J900D01*
G01D02*
Y703667D01*
G01D02*
G02X88442Y704582I1115J15D01*
G01D02*
G03X88900Y705497I-657J901D01*
G01D02*
Y706622D01*
G01D02*
G03X88442Y707537I-1115J14D01*
G01D02*
G02X87985Y708452I658J900D01*
G01D02*
Y709577D01*
G01D02*
G02X88442Y710492I1115J15D01*
G01D02*
G03X88900Y711407I-657J901D01*
G01D02*
Y719230D01*
G01D02*
G03X88442Y720145I-1115J14D01*
G01D02*
G02X87985Y721060I658J900D01*
G01D02*
Y722185D01*
G01D02*
G02X88442Y723100I1115J15D01*
G01D02*
G03X88900Y724015I-657J901D01*
G01D02*
Y731258D01*
G01X76999Y664550D02*
G02X78188Y662674I-3600J-3596D01*
G01D02*
G02X78469Y661402I-4787J-1725D01*
G01D02*
G03X78687Y660019I4504J1D01*
G01D02*
X78694Y659996D01*
G01D02*
G03X78759Y659810I3899J1258D01*
G01D02*
G03X79699Y658350I3837J1438D01*
G01D02*
X81771Y656278D01*
G01D02*
G02X84700Y649207I-7071J-7071D01*
G01X80499Y664550D02*
G03X79752Y663237I2014J-2015D01*
G01D02*
G03X79680Y662237I2761J-701D01*
G01D02*
X79816Y660947D01*
G01D02*
G03X79932Y660393I2782J293D01*
G01D02*
G03X79977Y660268I2653J884D01*
G01D02*
Y660267D01*
G01D02*
G03X80619Y659270I2619J981D01*
G01D02*
X82691Y657198D01*
G01D02*
G02X86000Y649207I-7991J-7990D01*
G01X50300Y699200D02*
X50260Y699161D01*
G01D02*
G02X47700Y698100I-2561J2560D01*
G01D02*
X40990D01*
G01D02*
G03X36400Y696199I-1J-6490D01*
G01D02*
X36399D01*
G01D02*
X27649Y687449D01*
G01D02*
X27650D01*
G01D02*
G02X23641Y685789I-4008J4008D01*
G01D02*
X21591D01*
G01D02*
G02X20943Y686058I1J917D01*
G01D02*
X20600Y686400D01*
G01D02*
X20268Y686733D01*
G01D02*
G03X19600Y687009I-667J-668D01*
G01D02*
X19594Y687003D01*
G01D02*
X12569D01*
G01X50410Y695801D02*
G03X47998Y696800I-2412J-2412D01*
G01D02*
X40989D01*
G01D02*
G03X37319Y695280I0J-5190D01*
G01D02*
X28569Y686530D01*
G01D02*
G02X23642Y684489I-4927J4927D01*
G01D02*
X21519D01*
G01D02*
G03X21134Y684427I3J-1243D01*
G01D02*
G03X20640Y684125I383J-1182D01*
G01D02*
X20073Y683558D01*
G01D02*
G02X18900Y683072I-1173J1173D01*
G01D02*
X18894Y683066D01*
G01D02*
X12569D01*
G01X92700Y730246D02*
G02X95000Y735800I7856J0D01*
G01D02*
X116506Y757306D01*
G01X95920Y734880D02*
G03X94000Y730245I4635J-4635D01*
G01X90200Y731258D02*
G02X92749Y737409I8699J-1D01*
G01D02*
X114191Y758851D01*
G01X88900Y731258D02*
G02X91829Y738329I10000J0D01*
G01D02*
X113271Y759771D01*
G01X85630Y957165D02*
X90498D01*
G01D02*
G02X91229Y956434I0J-731D01*
G01D02*
Y955702D01*
G01D02*
G03X91506Y955320I401J-1D01*
G01D02*
X91507D01*
G01D02*
G03X91629Y955302I119J382D01*
G01D02*
X99929D01*
G01X100349Y954002D02*
X91629D01*
G01D02*
G03X91229Y953602I0J-400D01*
G01D02*
Y952849D01*
G01D02*
G02X90940Y952369I-543J0D01*
G01D02*
X90893Y952344D01*
G01D02*
G02X90500Y952201I-709J1337D01*
G01D02*
X90197Y952169D01*
G01D02*
G02X90156Y952167I-40J390D01*
G01D02*
X89366D01*
G01D02*
X89364Y952165D01*
G01D02*
X85630D01*
G01X77166Y931535D02*
X80655D01*
G01D02*
G02X82038Y930962I0J-1956D01*
G01D02*
G03X83421Y930389I1383J1383D01*
G01D02*
X95622D01*
G01X77166Y928386D02*
X81048D01*
G01D02*
G03X82328Y928765I0J2351D01*
G01D02*
G02X83422Y929089I1095J-1687D01*
G01D02*
X96133D01*
G01X85630Y967165D02*
X90605D01*
G01D02*
G03X91041Y967342I1J624D01*
G01D02*
X91116Y967416D01*
G01D02*
G03X91229Y967684I-261J268D01*
G01D02*
Y968602D01*
G01D02*
G02X91540Y968991I399J0D01*
G01D02*
G02X91629Y969002I93J-388D01*
G01D02*
X94835D01*
G01D02*
G03X96399Y969651I-1J2212D01*
G01X85630Y972165D02*
X90498D01*
G01D02*
G02X91229Y971434I0J-731D01*
G01D02*
Y970702D01*
G01D02*
G03X91507Y970320I401J0D01*
G01D02*
G03X91536Y970312I121J383D01*
G01D02*
G03X91629Y970302I89J390D01*
G01D02*
X94834D01*
G01D02*
G03X95479Y970570I-1J911D01*
G01X77166Y937835D02*
X80741D01*
G01D02*
X80754Y937822D01*
G01D02*
G03X82149Y938400I0J1973D01*
G01D02*
G02X82994Y938750I845J-845D01*
G01D02*
X84592D01*
G01D02*
G02X85799Y938250I0J-1707D01*
G01D02*
X85975Y938074D01*
G01D02*
G02X86399Y937050I-1025J-1024D01*
G01X77166Y940984D02*
X80828D01*
G01D02*
X80841Y940971D01*
G01D02*
G02X82099Y940450I0J-1779D01*
G01D02*
X82146Y940404D01*
G01D02*
G03X82839Y940117I693J693D01*
G01D02*
X85246D01*
G01D02*
G03X85999Y940429I0J1065D01*
G01X108552Y996848D02*
X34903Y1070497D01*
G01X109472Y997768D02*
X35823Y1071417D01*
G01X97799Y999259D02*
G03X94490Y1007250I-11300J1D01*
G01D02*
X32123Y1069617D01*
G01X96499Y999259D02*
G03X93570Y1006330I-10000J0D01*
G01D02*
X31203Y1068697D01*
G01X116971Y999029D02*
X42476Y1073524D01*
G01X43396Y1074444D02*
X117891Y999949D01*
G01X114191Y998348D02*
X80896Y1031643D01*
G01D02*
X47602Y1064938D01*
G01X113271Y997428D02*
X46682Y1064018D01*
G01X124971Y1002729D02*
X55476Y1072225D01*
G01X56396Y1073145D02*
X91143Y1038397D01*
G01D02*
X125891Y1003649D01*
G01X121691Y1001749D02*
X47096Y1076343D01*
G01X120771Y1000829D02*
X46176Y1075423D01*
G01X66999Y1084550D02*
X141249Y1010300D01*
G01X142169Y1011220D02*
X67919Y1085470D01*
G01X138274Y1009614D02*
X66918Y1080970D01*
G01X137354Y1008694D02*
X65998Y1080050D01*
G01X133867Y1006681D02*
X62498Y1078050D01*
G01X134787Y1007601D02*
X63418Y1078970D01*
G01X95610Y1040230D02*
X61129Y1074710D01*
G01X129171Y1004829D02*
X60209Y1073790D01*
G01X34903Y1070497D02*
G02X31974Y1077568I7071J7071D01*
G01D02*
Y1382367D01*
G01X35823Y1071417D02*
G02X33274Y1077568I6150J6152D01*
G01D02*
Y1382368D01*
G01X32123Y1069617D02*
G02X29574Y1075768I6150J6152D01*
G01D02*
Y1380050D01*
G01X31203Y1068697D02*
G02X28274Y1075768I7071J7071D01*
G01D02*
Y1219384D01*
G01X42476Y1073524D02*
G02X39547Y1080595I7071J7071D01*
G01D02*
Y1395071D01*
G01X40847Y1395016D02*
Y1080595D01*
G01D02*
G03X43396Y1074444I8699J1D01*
G01X47602Y1064938D02*
X40894Y1071646D01*
G01D02*
G02X36999Y1081049I9402J9403D01*
G01D02*
Y1394318D01*
G01X46682Y1064018D02*
X39974Y1070726D01*
G01D02*
G02X35699Y1081050I10323J10321D01*
G01D02*
Y1394317D01*
G01X55476Y1072225D02*
X50908Y1076793D01*
G01D02*
G02X46947Y1086358I9568J9565D01*
G01D02*
Y1398586D01*
G01X48247Y1398587D02*
Y1086359D01*
G01D02*
G03X51828Y1077713I12228J0D01*
G01D02*
X56394Y1073147D01*
G01D02*
Y1073146D01*
G01D02*
G03X56396Y1073145I140J277D01*
G01X47096Y1076343D02*
G02X44547Y1082494I6150J6152D01*
G01D02*
Y1397051D01*
G01X46176Y1075423D02*
G02X43247Y1082494I7071J7071D01*
G01D02*
Y1397050D01*
G01X124615Y1038167D02*
X71615Y1091167D01*
G01D02*
X71616Y1091168D01*
G01D02*
G02X69599Y1096038I4869J4869D01*
G01D02*
Y1209859D01*
G01X70899Y1209858D02*
Y1096037D01*
G01D02*
G03X72535Y1092087I5586J0D01*
G01D02*
X125723Y1038899D01*
G01X133521Y1025367D02*
X68668Y1090220D01*
G01D02*
G02X67199Y1093766I3546J3546D01*
G01D02*
Y1215334D01*
G01X132601Y1024447D02*
X67748Y1089300D01*
G01D02*
G02X65899Y1093765I4467J4465D01*
G01D02*
Y1215335D01*
G01X61747Y1406310D02*
Y1092549D01*
G01D02*
G03X63689Y1087859I6632J-1D01*
G01D02*
X66999Y1084550D01*
G01X67919Y1085470D02*
X64609Y1088779D01*
G01D02*
G02X63048Y1092549I3771J3769D01*
G01D02*
X63047Y1092548D01*
G01D02*
Y1406309D01*
G01X66918Y1080970D02*
X61122Y1086768D01*
G01D02*
G02X59347Y1091050I4280J4283D01*
G01D02*
Y1403437D01*
G01X65998Y1080050D02*
X60202Y1085848D01*
G01D02*
G02X58047Y1091049I5201J5202D01*
G01D02*
Y1403436D01*
G01X62498Y1078050D02*
X56712Y1083838D01*
G01D02*
G02X54347Y1089546I5708J5709D01*
G01D02*
Y1401550D01*
G01X63418Y1078970D02*
X57632Y1084758D01*
G01D02*
G02X55647Y1089547I4787J4790D01*
G01D02*
Y1401550D01*
G01X61129Y1074710D02*
X54591Y1081248D01*
G01D02*
G02X52767Y1083875I6376J6374D01*
G01D02*
X52765Y1083878D01*
G01D02*
G02X51948Y1087629I8207J3752D01*
G01D02*
X51947Y1087628D01*
G01D02*
Y1401364D01*
G01X60209Y1073790D02*
X53671Y1080328D01*
G01D02*
G02X51581Y1083337I7301J7301D01*
G01D02*
G02X50647Y1087629I9391J4291D01*
G01D02*
Y1401363D01*
G01X28274Y1219384D02*
G03X27817Y1220299I-1115J15D01*
G01D02*
G02X27359Y1221214I657J901D01*
G01D02*
Y1222339D01*
G01D02*
G02X27817Y1223254I1115J14D01*
G01D02*
G03X28274Y1224169I-658J900D01*
G01D02*
Y1225294D01*
G01D02*
G03X27817Y1226209I-1115J15D01*
G01X69599Y1209859D02*
G02X71530Y1214519I6592J-1D01*
G01D02*
X71528D01*
G01D02*
X80504Y1223495D01*
G01D02*
G03X85900Y1236522I-13027J13027D01*
G01X87200Y1236519D02*
G02X81424Y1222575I-19720J0D01*
G01D02*
X72449Y1213600D01*
G01D02*
G03X70899Y1209858I3742J-3742D01*
G01X67199Y1215334D02*
G02X68668Y1218880I5015J0D01*
G01D02*
X75418Y1225630D01*
G01D02*
X75419D01*
G01D02*
X75493Y1225704D01*
G01D02*
G03X77499Y1230549I-4848J4845D01*
G01X65899Y1215335D02*
G02X67748Y1219799I6315J-1D01*
G01D02*
X74573Y1226624D01*
G01X27817Y1226209D02*
G02X27359Y1227124I657J901D01*
G01D02*
Y1228249D01*
G01D02*
G02X27817Y1229164I1115J14D01*
G01D02*
G03X28274Y1230079I-658J900D01*
G01D02*
Y1292873D01*
G01D02*
G03X27817Y1293788I-1115J15D01*
G01D02*
G02X27359Y1294703I657J901D01*
G01D02*
Y1295828D01*
G01D02*
G02X27817Y1296743I1115J14D01*
G01D02*
G03X28274Y1297658I-658J900D01*
G01D02*
Y1298783D01*
G01D02*
G03X27817Y1299698I-1115J15D01*
G01D02*
G02X27359Y1300613I657J901D01*
G01D02*
Y1301738D01*
G01D02*
G02X27817Y1302653I1115J14D01*
G01D02*
G03X28274Y1303568I-658J900D01*
G01D02*
Y1323568D01*
G01X85900Y1236522D02*
Y1243289D01*
G01D02*
G03X85119Y1246624I-7511J0D01*
G01D02*
G03X83700Y1248600I-6730J-3335D01*
G01D02*
X81727Y1250574D01*
G01D02*
G03X77800Y1252200I-3926J-3927D01*
G01D02*
X72449D01*
G01D02*
G02X71000Y1252800I0J2049D01*
G01D02*
G02X69999Y1255217I2417J2417D01*
G01D02*
Y1380358D01*
G01X71299Y1380359D02*
Y1255216D01*
G01D02*
X71300Y1255217D01*
G01D02*
G03X71920Y1253720I2117J0D01*
G01D02*
G03X72448Y1253500I530J528D01*
G01D02*
X77799D01*
G01D02*
G02X82647Y1251494I3J-6854D01*
G01D02*
X84620Y1249520D01*
G01D02*
G02X86284Y1247202I-6231J-6229D01*
G01D02*
G02X87200Y1243290I-7895J-3912D01*
G01D02*
Y1236519D01*
G01X77499Y1230549D02*
Y1235050D01*
G01D02*
X77490Y1235057D01*
G01D02*
X77434Y1235848D01*
G01D02*
G03X76184Y1238866I-4268J0D01*
G01D02*
X68999Y1246051D01*
G01D02*
X68998D01*
G01D02*
G02X67300Y1250153I4104J4101D01*
G01D02*
X67299Y1250152D01*
G01D02*
Y1391216D01*
G01X74573Y1226624D02*
G03X76199Y1230550I-3927J3926D01*
G01D02*
Y1234550D01*
G01D02*
G03X76184Y1234959I-5941J-13D01*
G01D02*
X76193Y1234968D01*
G01D02*
X76155Y1235502D01*
G01D02*
X76134Y1235802D01*
G01D02*
Y1235848D01*
G01D02*
G03X75264Y1237946I-2968J-1D01*
G01D02*
X68079Y1245131D01*
G01D02*
G02X65999Y1250153I5022J5022D01*
G01D02*
Y1391217D01*
G01X85630Y1362677D02*
X91030D01*
G01D02*
G02X91499Y1362208I0J-469D01*
G01D02*
Y1361739D01*
G01D02*
G03X92029Y1360900I928J-1D01*
G01D02*
G03X92092Y1360873I397J839D01*
G01D02*
G03X92100Y1360871I228J894D01*
G01D02*
G03X92155Y1360853I316J871D01*
G01D02*
G03X92268Y1360826I271J885D01*
G01D02*
G03X92422Y1360813I155J913D01*
G01D02*
G03X92424Y1360814I-413J829D01*
G01D02*
X102135D01*
G01X85630Y1357677D02*
X90751D01*
G01D02*
G03X91339Y1358265I0J588D01*
G01D02*
Y1358853D01*
G01D02*
G02X91999Y1359513I660J0D01*
G01D02*
G02X92040Y1359514I35J-610D01*
G01D02*
X102265D01*
G01X77166Y1337047D02*
X80790D01*
G01D02*
X80803Y1337034D01*
G01D02*
G02X81991Y1336542I0J-1680D01*
G01D02*
G03X83179Y1336050I1188J1188D01*
G01D02*
X98400D01*
G01X77166Y1333898D02*
X80251D01*
G01D02*
X80264Y1333885D01*
G01D02*
G03X81749Y1334500I0J2100D01*
G01D02*
G02X82353Y1334750I604J-604D01*
G01D02*
X98099D01*
G01X85630Y1372677D02*
X90287D01*
G01D02*
G03X90952Y1372952I0J942D01*
G01D02*
X91062Y1373061D01*
G01D02*
G03X91229Y1373464I-403J403D01*
G01D02*
Y1374114D01*
G01D02*
G02X91508Y1374495I400J0D01*
G01D02*
G02X91629Y1374514I122J-381D01*
G01D02*
X94975D01*
G01D02*
G02X96813Y1373753I0J-2600D01*
G01X25507Y1372045D02*
X24773Y1371311D01*
G01D02*
G02X23322Y1370710I-1451J1451D01*
G01D02*
X21674D01*
G01D02*
G02X20262Y1371295I0J1997D01*
G01D02*
G03X18447Y1372047I-1815J-1815D01*
G01D02*
X18441Y1372041D01*
G01D02*
X12569D01*
G01X25558Y1368447D02*
G03X23233Y1369410I-2325J-2325D01*
G01D02*
X21899D01*
G01D02*
G03X20910Y1369001I-1J-1398D01*
G01D02*
X20719Y1368809D01*
G01D02*
G02X19031Y1368110I-1688J1688D01*
G01D02*
X19025Y1368104D01*
G01D02*
X12569D01*
G01X85630Y1377677D02*
X90707D01*
G01D02*
G02X91076Y1377524I0J-521D01*
G01D02*
G02X91229Y1377155I-368J-369D01*
G01D02*
Y1376214D01*
G01D02*
G03X91506Y1375833I401J0D01*
G01D02*
G03X91629Y1375814I122J381D01*
G01D02*
X93400D01*
G01D02*
G03X96496Y1377097I-1J4379D01*
G01X77166Y1343347D02*
X80840D01*
G01D02*
X80853Y1343334D01*
G01D02*
G03X82099Y1343850I0J1762D01*
G01D02*
G02X82582Y1344050I483J-483D01*
G01D02*
X84017D01*
G01D02*
G02X86890Y1342860I0J-4063D01*
G01X77166Y1346496D02*
X80134D01*
G01D02*
X80147Y1346483D01*
G01D02*
G02X82399Y1345550I0J-3185D01*
G01D02*
G03X82882Y1345350I483J483D01*
G01D02*
X83799D01*
G01D02*
G03X86882Y1346627I0J4360D01*
G01D02*
X86890Y1346635D01*
G01X31974Y1382367D02*
G03X31195Y1384246I-2656J0D01*
G01D02*
X31044Y1384397D01*
G01D02*
X31042Y1384402D01*
G01D02*
X30384Y1385061D01*
G01D02*
G02X29628Y1386937I1951J1877D01*
G01D02*
Y1389200D01*
G01D02*
G03X29118Y1390431I-1741J0D01*
G01D02*
X28499Y1391050D01*
G01X33274Y1382368D02*
G03X32115Y1385166I-3957J0D01*
G01D02*
X32113Y1385168D01*
G01D02*
X32111Y1385172D01*
G01D02*
X31314Y1385970D01*
G01D02*
G02X30928Y1386938I1021J968D01*
G01D02*
Y1387550D01*
G01D02*
G02X31231Y1388280I1033J-1D01*
G01D02*
X32333Y1389383D01*
G01X29574Y1380050D02*
G03X28309Y1383105I-4321J0D01*
G01D02*
X26681Y1384733D01*
G01D02*
X26489Y1384924D01*
G01D02*
G03X22872Y1386457I-3616J-3497D01*
G01D02*
X21476D01*
G01D02*
G02X20522Y1386852I0J1349D01*
G01D02*
G03X18245Y1387795I-2277J-2277D01*
G01D02*
X18239Y1387789D01*
G01D02*
X12569D01*
G01X28274Y1323568D02*
G03X27817Y1324483I-1115J15D01*
G01D02*
G02X27359Y1325398I657J901D01*
G01D02*
Y1326523D01*
G01D02*
G02X27817Y1327438I1115J14D01*
G01D02*
G03X28274Y1328353I-658J900D01*
G01D02*
Y1329478D01*
G01D02*
G03X27817Y1330393I-1115J15D01*
G01D02*
G02X27359Y1331308I657J901D01*
G01D02*
Y1332433D01*
G01D02*
G02X27817Y1333348I1115J14D01*
G01D02*
G03X28274Y1334263I-658J900D01*
G01D02*
Y1335388D01*
G01D02*
G03X27817Y1336303I-1115J15D01*
G01D02*
G02X27359Y1337218I657J901D01*
G01D02*
Y1338343D01*
G01D02*
G02X27817Y1339258I1115J14D01*
G01D02*
G03X28274Y1340173I-658J900D01*
G01D02*
Y1380051D01*
G01D02*
X28273Y1380050D01*
G01D02*
G03X27389Y1382185I-3020J0D01*
G01D02*
X25512Y1384062D01*
G01D02*
X25510Y1384065D01*
G01D02*
G03X22872Y1385157I-2637J-2638D01*
G01D02*
X21699D01*
G01D02*
G03X21052Y1384889I0J-915D01*
G01D02*
X20719Y1384556D01*
G01D02*
G02X19034Y1383858I-1685J1685D01*
G01D02*
X19028Y1383852D01*
G01D02*
X12569D01*
G01X69999Y1380358D02*
G02X71681Y1384419I5742J1D01*
G01D02*
X71680D01*
G01D02*
X73180Y1385919D01*
G01D02*
X73181D01*
G01D02*
G02X76757Y1387400I3575J-3575D01*
G01D02*
X83327D01*
G01D02*
G03X85500Y1388300I0J3073D01*
G01D02*
X86600Y1389400D01*
G01D02*
G03X87491Y1391551I-2151J2151D01*
G01X88791Y1391550D02*
G02X87519Y1388481I-4342J1D01*
G01D02*
Y1388480D01*
G01D02*
X86419Y1387380D01*
G01D02*
Y1387381D01*
G01D02*
G02X83326Y1386100I-3092J3092D01*
G01D02*
X76756D01*
G01D02*
G03X74100Y1385000I0J-3756D01*
G01D02*
X72600Y1383500D01*
G01D02*
G03X71299Y1380359I3141J-3141D01*
G01X67299Y1391216D02*
G02X69550Y1396650I7685J0D01*
G01X65999Y1391217D02*
G02X68630Y1397569I8985J-1D01*
G01X39547Y1395071D02*
G03X38491Y1397991I-3642J334D01*
G01D02*
X31198Y1405284D01*
G01D02*
G02X30199Y1407697I2415J2413D01*
G01D02*
Y1409050D01*
G01D02*
G03X29280Y1411269I-3138J0D01*
G01D02*
X28999Y1411550D01*
G01X32451Y1411468D02*
G03X31499Y1409170I2298J-2298D01*
G01D02*
Y1407698D01*
G01D02*
G03X32118Y1406204I2113J0D01*
G01D02*
X39411Y1398911D01*
G01D02*
G02X40847Y1395016I-3507J-3505D01*
G01X36999Y1394318D02*
G03X36100Y1396488I-3069J0D01*
G01D02*
X27985Y1404603D01*
G01D02*
G02X27799Y1405051I448J448D01*
G01D02*
Y1405887D01*
G01D02*
G03X26712Y1408515I-3715J2D01*
G01D02*
G03X25428Y1409335I-2501J-2501D01*
G01D02*
G03X24216Y1409550I-1212J-3306D01*
G01D02*
X23311D01*
G01D02*
G02X22683Y1409810I0J888D01*
G01D02*
G03X22108Y1410048I-575J-575D01*
G01D02*
X21751D01*
G01D02*
G02X21426Y1410077I-2J1811D01*
G01D02*
G02X21205Y1410131I319J1784D01*
G01D02*
G02X20470Y1410578I547J1727D01*
G01D02*
X20455Y1410594D01*
G01D02*
G03X18463Y1411419I-1992J-1992D01*
G01D02*
X18457Y1411413D01*
G01D02*
X12569D01*
G01X35699Y1394317D02*
G03X35180Y1395568I-1769J-1D01*
G01D02*
X34804Y1395944D01*
G01D02*
Y1395945D01*
G01D02*
X27555Y1403193D01*
G01D02*
X27066Y1403683D01*
G01D02*
G02X26499Y1405050I1367J1368D01*
G01D02*
Y1405888D01*
G01D02*
G03X25792Y1407595I-2414J0D01*
G01D02*
G03X24980Y1408113I-1581J-1582D01*
G01D02*
G03X24211Y1408250I-771J-2099D01*
G01D02*
X22841D01*
G01D02*
G02X22257Y1408492I0J826D01*
G01D02*
G03X21635Y1408750I-623J-622D01*
G01D02*
G03X21149Y1408548I1J-688D01*
G01D02*
X20500Y1407900D01*
G01D02*
X20329Y1407729D01*
G01D02*
G02X19730Y1407481I-599J599D01*
G01D02*
X12575D01*
G01D02*
X12569Y1407475D01*
G01X46947Y1398586D02*
G03X45708Y1401577I-4230J0D01*
G01D02*
X40767Y1406516D01*
G01D02*
X40768Y1406517D01*
G01D02*
G02X39316Y1410023I3505J3505D01*
G01D02*
Y1415834D01*
G01D02*
G03X38530Y1417732I-2684J0D01*
G01D02*
X32605Y1423657D01*
G01D02*
X32606Y1423658D01*
G01D02*
G02X31199Y1427055I3396J3396D01*
G01D02*
Y1431504D01*
G01D02*
G03X31017Y1432422I-2400J1D01*
G01D02*
X30661Y1433281D01*
G01D02*
G02X30499Y1434093I1960J813D01*
G01D02*
Y1434550D01*
G01X33206Y1432352D02*
G03X32499Y1430645I1707J-1707D01*
G01D02*
Y1427054D01*
G01D02*
G03X33525Y1424577I3503J0D01*
G01D02*
X39450Y1418652D01*
G01D02*
X39449Y1418651D01*
G01D02*
G02X40616Y1415833I-2817J-2817D01*
G01D02*
Y1410022D01*
G01D02*
G03X41687Y1407436I3657J0D01*
G01D02*
X41688Y1407437D01*
G01D02*
X42607Y1406517D01*
G01D02*
X42606Y1406516D01*
G01D02*
X46628Y1402497D01*
G01D02*
G02X48247Y1398587I-3912J-3910D01*
G01X44547Y1397051D02*
G03X42928Y1400961I-5531J0D01*
G01D02*
X42679Y1401210D01*
G01D02*
X42678D01*
G01D02*
X38174Y1405714D01*
G01D02*
G02X36916Y1408751I3037J3037D01*
G01D02*
Y1414287D01*
G01D02*
G03X35739Y1417130I-4022J0D01*
G01D02*
X29823Y1423046D01*
G01D02*
G03X23102Y1425830I-6721J-6721D01*
G01D02*
X21443D01*
G01D02*
G02X20557Y1426197I0J1253D01*
G01D02*
G03X18215Y1427167I-2342J-2342D01*
G01D02*
X18209Y1427161D01*
G01D02*
X12569D01*
G01X43247Y1397050D02*
G03X42008Y1400041I-4230J0D01*
G01D02*
X37254Y1404794D01*
G01D02*
X37255Y1404795D01*
G01D02*
G02X35616Y1408750I3956J3956D01*
G01D02*
Y1414286D01*
G01D02*
G03X34819Y1416210I-2721J0D01*
G01D02*
X28903Y1422126D01*
G01D02*
G03X23100Y1424530I-5803J-5802D01*
G01D02*
X21356D01*
G01D02*
G03X20634Y1424231I0J-1021D01*
G01D02*
G02X18217Y1423230I-2417J2417D01*
G01D02*
X18211Y1423224D01*
G01D02*
X12569D01*
G01X98829Y1462881D02*
X48416Y1513294D01*
G01X99749Y1463800D02*
X49335Y1514214D01*
G01X95918Y1460970D02*
X43918Y1512970D01*
G01X94999Y1460050D02*
X42999Y1512050D01*
G01X95616Y1425168D02*
X95040Y1425745D01*
G01D02*
G02X94067Y1426973I4804J4806D01*
G01D02*
G02X93049Y1430550I5778J3578D01*
G01D02*
Y1452050D01*
G01D02*
G03X91505Y1455778I-5273J0D01*
G01D02*
X41866Y1505417D01*
G01X95173Y1427658D02*
G02X94349Y1430550I4672J2894D01*
G01D02*
Y1452051D01*
G01D02*
G03X92425Y1456698I-6574J0D01*
G01D02*
X42787Y1506336D01*
G01X240321Y1277068D02*
X92918Y1424470D01*
G01D02*
G02X90649Y1429948I5474J5476D01*
G01D02*
Y1450050D01*
G01D02*
G03X88394Y1455494I-7699J0D01*
G01D02*
X41120Y1502768D01*
G01X239352Y1276197D02*
X92303Y1423246D01*
G01D02*
X91998Y1423549D01*
G01D02*
Y1423550D01*
G01D02*
G02X89349Y1429948I6395J6395D01*
G01D02*
Y1450049D01*
G01D02*
G03X87474Y1454574I-6399J0D01*
G01D02*
X40649Y1501399D01*
G01X214569Y1295366D02*
X87191Y1422744D01*
G01D02*
G02X85149Y1427674I4932J4931D01*
G01D02*
Y1439430D01*
G01D02*
G03X83831Y1442612I-4500J0D01*
G01D02*
X75403Y1451040D01*
G01D02*
X67067Y1459375D01*
G01D02*
X37971Y1488472D01*
G01X36616Y1491667D02*
X84750Y1443532D01*
G01D02*
G02X86449Y1439431I-4101J-4101D01*
G01D02*
Y1427675D01*
G01D02*
G03X88111Y1423663I5674J0D01*
G01D02*
X215490Y1296284D01*
G01X95826Y1410714D02*
X84494Y1422046D01*
G01D02*
G02X82749Y1426259I4213J4213D01*
G01D02*
Y1437050D01*
G01D02*
G03X80954Y1441386I-6131J1D01*
G01D02*
X79420Y1442920D01*
G01D02*
X79419D01*
G01D02*
X35417Y1486922D01*
G01X210346Y1294347D02*
X94526Y1410174D01*
G01D02*
Y1410175D01*
G01D02*
X83575Y1421126D01*
G01D02*
G02X81449Y1426259I5133J5133D01*
G01D02*
Y1437050D01*
G01D02*
G03X80034Y1440466I-4831J0D01*
G01D02*
X34500Y1486000D01*
G01X87491Y1391551D02*
Y1398100D01*
G01D02*
G03X85236Y1403545I-7701J0D01*
G01D02*
X85140Y1403641D01*
G01D02*
X84799Y1403983D01*
G01D02*
X81739Y1407044D01*
G01D02*
X81712Y1407072D01*
G01D02*
X81710Y1407071D01*
G01D02*
X75472Y1413311D01*
G01D02*
Y1413312D01*
G01D02*
G03X71999Y1414750I-3472J-3473D01*
G01D02*
X67193D01*
G01D02*
G02X64359Y1415924I0J4008D01*
G01D02*
X63366Y1416917D01*
G01D02*
G02X62081Y1420019I3102J3102D01*
G01D02*
Y1446335D01*
G01D02*
G03X60294Y1450649I-6101J0D01*
G01D02*
X34445Y1476497D01*
G01X34282Y1478500D02*
X61213Y1451569D01*
G01D02*
G02X63381Y1446334I-5236J-5235D01*
G01D02*
Y1420019D01*
G01D02*
G03X64286Y1417837I3086J1D01*
G01D02*
X65277Y1416845D01*
G01D02*
G03X67196Y1416050I1919J1919D01*
G01D02*
X71999D01*
G01D02*
G02X76392Y1414231I1J-6212D01*
G01D02*
X81710Y1408910D01*
G01D02*
X81711Y1408911D01*
G01D02*
Y1408912D01*
G01D02*
X82659Y1407964D01*
G01D02*
X85719Y1404902D01*
G01D02*
X85720D01*
G01D02*
X86060Y1404560D01*
G01D02*
X86156Y1404465D01*
G01D02*
G02X88791Y1398100I-6367J-6364D01*
G01D02*
Y1391550D01*
G01X69550Y1396650D02*
X75199Y1402299D01*
G01D02*
X75200D01*
G01D02*
X75584Y1402683D01*
G01D02*
G03X76543Y1404999I-2317J2316D01*
G01D02*
Y1407399D01*
G01D02*
G03X75524Y1409863I-3483J2D01*
G01D02*
X75493Y1409894D01*
G01D02*
X75492Y1409893D01*
G01D02*
X74318Y1411068D01*
G01D02*
G03X71479Y1412244I-2839J-2839D01*
G01D02*
X65775D01*
G01D02*
G02X63844Y1413044I0J2731D01*
G01D02*
X61168Y1415720D01*
G01D02*
G02X59681Y1419310I3590J3590D01*
G01D02*
Y1444551D01*
G01D02*
G03X57337Y1450210I-8003J0D01*
G01D02*
X36498Y1471050D01*
G01D02*
G03X31600Y1473079I-4898J-4898D01*
G01D02*
X22599D01*
G01D02*
G02X22597I-1J1736D01*
G01D02*
G02X21273Y1473628I0J1871D01*
G01D02*
G03X19383Y1474411I-1890J-1890D01*
G01X68630Y1397569D02*
X74664Y1403603D01*
G01D02*
G03X75243Y1405000I-1396J1397D01*
G01D02*
Y1407400D01*
G01D02*
G03X74604Y1408943I-2182J0D01*
G01D02*
X73399Y1410148D01*
G01D02*
G03X71478Y1410944I-1921J-1919D01*
G01D02*
X65774D01*
G01D02*
G02X62925Y1412125I2J4031D01*
G01D02*
X62924Y1412124D01*
G01D02*
X61925Y1413123D01*
G01D02*
X60249Y1414800D01*
G01D02*
G02X58381Y1419310I4509J4509D01*
G01D02*
Y1444550D01*
G01D02*
G03X56417Y1449292I-6706J0D01*
G01D02*
X56416Y1449291D01*
G01D02*
X50603Y1455104D01*
G01D02*
X35578Y1470130D01*
G01D02*
X35579D01*
G01D02*
G03X31599Y1471779I-3980J-3978D01*
G01D02*
X22380D01*
G01D02*
G03X21602Y1471591I0J-1704D01*
G01D02*
X21381Y1471477D01*
G01D02*
G03X21000Y1471200I692J-1352D01*
G01D02*
G02X19247Y1470474I-1753J1753D01*
G01D02*
X19241Y1470468D01*
G01D02*
X12569D01*
G01X30378Y1462518D02*
X30425D01*
G01D02*
X53382Y1439561D01*
G01D02*
G02X54116Y1437789I-1772J-1772D01*
G01D02*
Y1417839D01*
G01D02*
G03X55383Y1414356I5415J-2D01*
G01D02*
G03X55712Y1413997I4276J3588D01*
G01D02*
X60579Y1409130D01*
G01D02*
G02X61747Y1406310I-2820J-2820D01*
G01X63047Y1406309D02*
G03X61498Y1410049I-5288J1D01*
G01D02*
X61499Y1410050D01*
G01D02*
X61498Y1410051D01*
G01D02*
X56621Y1414930D01*
G01D02*
G02X55416Y1417839I2909J2909D01*
G01D02*
Y1433589D01*
G01D02*
X55421Y1433594D01*
G01D02*
Y1434670D01*
G01D02*
X55416Y1434675D01*
G01D02*
Y1437790D01*
G01D02*
G03X54301Y1440480I-3806J-1D01*
G01D02*
X54302Y1440481D01*
G01D02*
X34867Y1459915D01*
G01D02*
X34391Y1460392D01*
G01D02*
G02X33915Y1461541I1149J1149D01*
G01D02*
Y1462681D01*
G01X59347Y1403437D02*
G03X57220Y1408570I-7261J-2D01*
G01D02*
X57221Y1408571D01*
G01D02*
X54289Y1411502D01*
G01D02*
X54290Y1411503D01*
G01D02*
X53371Y1412423D01*
G01D02*
X53370Y1412422D01*
G01D02*
G02X51716Y1416415I3993J3993D01*
G01D02*
Y1435249D01*
G01D02*
G03X50003Y1439385I-5849J0D01*
G01D02*
X49668Y1439719D01*
G01D02*
X33918Y1455469D01*
G01D02*
X33919Y1455470D01*
G01D02*
X33835Y1455554D01*
G01D02*
G03X29500Y1457349I-4335J-4337D01*
G01D02*
X22691D01*
G01D02*
G02X22504Y1457356I-4J2393D01*
G01D02*
G02X21217Y1457857I188J2386D01*
G01D02*
G03X19271Y1458663I-1946J-1946D01*
G01D02*
X19265Y1458657D01*
G01D02*
X12569D01*
G01X58047Y1403436D02*
G03X56301Y1407650I-5961J-1D01*
G01D02*
Y1407651D01*
G01D02*
X52450Y1411502D01*
G01D02*
X52451Y1411503D01*
G01D02*
G02X50416Y1416414I4912J4912D01*
G01D02*
Y1435250D01*
G01D02*
X50415Y1435249D01*
G01D02*
G03X49084Y1438466I-4549J2D01*
G01D02*
Y1438465D01*
G01D02*
X48749Y1438799D01*
G01D02*
X32998Y1454550D01*
G01D02*
G03X32916Y1454635I-3518J-3312D01*
G01D02*
X32915Y1454634D01*
G01D02*
G03X29499Y1456049I-3416J-3416D01*
G01D02*
X22402D01*
G01D02*
G03X21602Y1455904I2J-2291D01*
G01D02*
X21597Y1455902D01*
G01D02*
G03X20782Y1455378I799J-2139D01*
G01D02*
G02X19208Y1454726I-1574J1574D01*
G01D02*
X19202Y1454720D01*
G01D02*
X12569D01*
G01X54347Y1401550D02*
G03X52353Y1406365I-6810J0D01*
G01D02*
X52211Y1406507D01*
G01D02*
Y1406509D01*
G01D02*
X52205Y1406515D01*
G01D02*
X51218Y1407501D01*
G01D02*
X51199D01*
G01D02*
X47999Y1410700D01*
G01D02*
G02X46716Y1413799I3101J3099D01*
G01D02*
Y1429208D01*
G01D02*
G03X45398Y1432390I-4500J0D01*
G01D02*
X33634Y1444154D01*
G01D02*
G03X31471Y1445050I-2163J-2163D01*
G01D02*
Y1445049D01*
G01D02*
G02X29627Y1447462I1J1912D01*
G01D02*
G03X28989Y1448296I-638J173D01*
G01D02*
X28697D01*
G01X55647Y1401550D02*
G03X53273Y1407285I-8111J2D01*
G01D02*
X52880Y1407680D01*
G01D02*
X51757Y1408801D01*
G01D02*
X51738D01*
G01D02*
X48919Y1411620D01*
G01D02*
G02X48016Y1413800I2180J2180D01*
G01D02*
Y1429210D01*
G01D02*
G03X46317Y1433311I-5800J0D01*
G01D02*
X34554Y1445074D01*
G01D02*
G03X31471Y1446351I-3083J-3083D01*
G01D02*
X31472Y1446350D01*
G01D02*
G02X30882Y1447121I-1J611D01*
G01D02*
G02X31040Y1447393I589J-160D01*
G01D02*
X32094Y1448448D01*
G01X51947Y1401364D02*
G03X51946Y1401418I-1458J0D01*
G01D02*
G03X50412Y1404912I-5251J-222D01*
G01D02*
X45638Y1409686D01*
G01D02*
G02X44316Y1412873I3182J3188D01*
G01D02*
Y1427049D01*
G01D02*
G03X42181Y1432207I-7292J2D01*
G01D02*
X33909Y1440480D01*
G01D02*
G03X31256Y1441578I-2653J-2656D01*
G01D02*
X21521D01*
G01D02*
G02X20471Y1442013I0J1485D01*
G01D02*
G03X18293Y1442915I-2178J-2178D01*
G01D02*
X18287Y1442909D01*
G01D02*
X12569D01*
G01X50647Y1401363D02*
G03X49492Y1403992I-3952J-168D01*
G01D02*
X44718Y1408766D01*
G01D02*
G02X43016Y1412872I4102J4106D01*
G01D02*
Y1427050D01*
G01D02*
G03X41261Y1431287I-5992J0D01*
G01D02*
X32987Y1439561D01*
G01D02*
G03X31256Y1440278I-1731J-1731D01*
G01D02*
X21443D01*
G01D02*
G03X20535Y1439902I0J-1284D01*
G01D02*
G02X18304Y1438978I-2231J2231D01*
G01D02*
X18298Y1438972D01*
G01D02*
X12569D01*
G01X48416Y1513294D02*
G02X46317Y1518362I5067J5067D01*
G01D02*
Y1521470D01*
G01D02*
X46318Y1521471D01*
G01D02*
Y1535050D01*
G01D02*
G03X42554Y1543510I-11389J0D01*
G01D02*
X42528Y1543532D01*
G01D02*
X30266Y1555794D01*
G01D02*
G02X28049Y1561050I5121J5255D01*
G01X49335Y1514214D02*
G02X47617Y1518362I4148J4148D01*
G01D02*
Y1520931D01*
G01D02*
X47618Y1520932D01*
G01D02*
Y1535050D01*
G01D02*
G03X43424Y1544476I-12689J0D01*
G01D02*
X32174Y1555726D01*
G01D02*
G03X31174Y1556725I-999000J-999000D01*
G01D02*
G02X29349Y1561050I4212J4325D01*
G01X43918Y1512970D02*
G02X41881Y1517888I4918J4918D01*
G01D02*
Y1537615D01*
G01D02*
G03X40543Y1540845I-4569J-1D01*
G01D02*
X26721Y1554668D01*
G01D02*
G03X24104Y1555751I-2616J-2617D01*
G01D02*
X22126D01*
G01D02*
G02X21131Y1556163I0J1407D01*
G01D02*
G03X18898Y1557088I-2233J-2233D01*
G01X42999Y1512050D02*
G02X40581Y1517888I5837J5837D01*
G01D02*
Y1537614D01*
G01D02*
G03X39623Y1539925I-3269J-1D01*
G01D02*
X25801Y1553748D01*
G01D02*
G03X24104Y1554451I-1697J-1697D01*
G01D02*
X21606D01*
G01D02*
G03X20628Y1554046I0J-1383D01*
G01D02*
G02X18467Y1553151I-2161J2161D01*
G01D02*
X18461Y1553145D01*
G01D02*
X12569D01*
G01X41866Y1505417D02*
X41586Y1505698D01*
G01D02*
G03X38499Y1506976I-3086J-3087D01*
G01D02*
X36127D01*
G01D02*
G02X32724Y1508385I0J4813D01*
G01D02*
X32149Y1508961D01*
G01D02*
G02X31386Y1510802I1840J1841D01*
G01D02*
G03X30288Y1511900I-1098J0D01*
G01D02*
X30115D01*
G01X42787Y1506336D02*
X42507Y1506617D01*
G01D02*
G03X38499Y1508276I-4006J-4007D01*
G01D02*
X36128D01*
G01D02*
G02X33644Y1509305I0J3513D01*
G01D02*
X33068Y1509881D01*
G01D02*
G02X32686Y1510802I919J921D01*
G01D02*
Y1511225D01*
G01D02*
G02X33512Y1512051I826J0D01*
G01X41120Y1502768D02*
G03X36768Y1504570I-4351J-4351D01*
G01D02*
X21653D01*
G01D02*
G02X20724Y1504955I0J1314D01*
G01D02*
G03X18426Y1505907I-2298J-2298D01*
G01D02*
X18420Y1505901D01*
G01D02*
X12569D01*
G01X40649Y1501399D02*
X40648D01*
G01D02*
X40200Y1501847D01*
G01D02*
Y1501849D01*
G01D02*
G03X36768Y1503270I-3431J-3432D01*
G01D02*
X21613D01*
G01D02*
G03X20751Y1502913I0J-1219D01*
G01D02*
G02X18474Y1501970I-2277J2277D01*
G01D02*
X18468Y1501964D01*
G01D02*
X12569D01*
G01X37971Y1488472D02*
X35946Y1490497D01*
G01D02*
Y1490498D01*
G01D02*
X35697Y1490748D01*
G01D02*
X35453Y1491004D01*
G01D02*
G03X34087Y1491686I-2362J-3022D01*
G01D02*
X34086Y1491684D01*
G01D02*
G02X34084Y1491685I1227J2457D01*
G01D02*
G02X32899Y1492355I717J2651D01*
G01D02*
X32886Y1492366D01*
G01D02*
X32850Y1492401D01*
G01D02*
X32600Y1492651D01*
G01D02*
G02X31649Y1494950I2300J2297D01*
G01D02*
Y1495550D01*
G01D02*
G03X31048Y1497001I-2052J0D01*
G01D02*
X30499Y1497550D01*
G01X34099D02*
X33550Y1497001D01*
G01D02*
G03X32949Y1495550I1451J-1451D01*
G01D02*
Y1494950D01*
G01D02*
G03X33520Y1493571I1950J0D01*
G01D02*
X33770Y1493321D01*
G01D02*
X33777Y1493315D01*
G01D02*
G03X34423Y1492941I1023J1022D01*
G01D02*
G02X36253Y1492029I-1330J-4961D01*
G01D02*
X36616Y1491667D01*
G01X35417Y1486922D02*
X35248Y1487090D01*
G01D02*
G03X31001Y1488849I-4248J-4249D01*
G01D02*
X21881D01*
G01D02*
G02X20978Y1489223I0J1277D01*
G01D02*
G03X18718Y1490159I-2260J-2260D01*
G01D02*
X18712Y1490153D01*
G01D02*
X12569D01*
G01X34500Y1486000D02*
X34330Y1486169D01*
G01D02*
X34329Y1486170D01*
G01D02*
G03X31000Y1487549I-3329J-3329D01*
G01D02*
X21954D01*
G01D02*
G03X20865Y1487098I0J-1540D01*
G01D02*
G02X18750Y1486222I-2115J2115D01*
G01D02*
X18744Y1486216D01*
G01D02*
X12569D01*
G01X31999Y1521500D02*
X31396Y1520896D01*
G01D02*
G02X29999Y1520318I-1396J1397D01*
G01D02*
X22444D01*
G01D02*
G02X20930Y1520945I0J2141D01*
G01D02*
G03X19216Y1521655I-1714J-1714D01*
G01D02*
X19210Y1521649D01*
G01D02*
X12569D01*
G01X31999Y1517846D02*
X31416Y1518429D01*
G01D02*
G03X30298Y1518995I-1422J-1421D01*
G01D02*
G03X29999Y1519018I-302J-1976D01*
G01D02*
X22376D01*
G01D02*
G03X21947Y1518975I3J-2192D01*
G01D02*
G03X20826Y1518376I428J-2150D01*
G01D02*
G02X19237Y1517718I-1589J1589D01*
G01D02*
X19231Y1517712D01*
G01D02*
X12569D01*
G01X34445Y1476497D02*
X33497Y1477445D01*
G01D02*
X33362Y1477581D01*
G01D02*
X32488Y1478455D01*
G01D02*
G02X30999Y1482050I3595J3595D01*
G01X34465Y1481683D02*
X34318D01*
G01D02*
G03X32999Y1480364I0J-1319D01*
G01D02*
G03X33409Y1479374I1400J0D01*
G01D02*
X34076Y1478707D01*
G01D02*
X34282Y1478500D01*
G01X19383Y1474411D02*
X19377Y1474405D01*
G01D02*
X12569D01*
G01X42249Y1639801D02*
G02X38936Y1638428I-3313J3311D01*
G01D02*
X21444D01*
G01D02*
G02X20556Y1638796I0J1256D01*
G01D02*
G03X18217Y1639765I-2339J-2339D01*
G01X59418Y1655130D02*
X43169Y1638881D01*
G01D02*
G02X38937Y1637128I-4232J4232D01*
G01D02*
X21500D01*
G01D02*
G03X20464Y1636699I0J-1465D01*
G01D02*
G02X18361Y1635828I-2103J2103D01*
G01D02*
X18355Y1635822D01*
G01D02*
X12569D01*
G01X62834Y1652484D02*
X36643Y1626293D01*
G01D02*
G02X34149Y1625260I-2494J2494D01*
G01D02*
X32896D01*
G01D02*
G02X31985Y1625638I1J1289D01*
G01D02*
X31776Y1625846D01*
G01D02*
G02X30906Y1627534I2204J2204D01*
G01D02*
G03X30122Y1629427I-2677J0D01*
G01D02*
X29499Y1630050D01*
G01X32663Y1628181D02*
Y1627143D01*
G01D02*
G03X33246Y1626560I583J0D01*
G01D02*
X34419D01*
G01D02*
G03X35532Y1627021I0J1574D01*
G01D02*
X62030Y1653519D01*
G01X76805Y1642103D02*
G02X78278Y1638551I-3551J-3554D01*
G01D02*
Y1626980D01*
G01D02*
G02X77279Y1624570I-3407J0D01*
G01D02*
G02X72718Y1622680I-4561J4559D01*
G01D02*
X21605D01*
G01D02*
G02X20777Y1623023I0J1171D01*
G01D02*
G03X18377Y1624017I-2400J-2400D01*
G01D02*
X18371Y1624011D01*
G01D02*
X12569D01*
G01X77725Y1643023D02*
G02X79578Y1638551I-4472J-4473D01*
G01D02*
Y1626979D01*
G01D02*
G02X78199Y1623650I-4708J0D01*
G01D02*
G02X72719Y1621380I-5480J5480D01*
G01D02*
X21668D01*
G01D02*
G03X20683Y1620972I0J-1393D01*
G01D02*
G02X18530Y1620080I-2153J2153D01*
G01D02*
X18524Y1620074D01*
G01D02*
X12569D01*
G01X324499Y1609417D02*
X32734D01*
G01D02*
G02X29999Y1610550I0J3868D01*
G01D02*
G02X28899Y1613206I2656J2656D01*
G01D02*
Y1613524D01*
G01X324500Y1610717D02*
X32735D01*
G01D02*
G02X30919Y1611470I0J2567D01*
G01D02*
G02X30878Y1611513I1756J1715D01*
G01D02*
G02X30895Y1612446I492J458D01*
G01D02*
X31743Y1613293D01*
G01D02*
G02X32299Y1613524I557J-556D01*
G01X322999Y1606849D02*
X21733D01*
G01D02*
G02X21656Y1606851I-2J1417D01*
G01D02*
G02X20732Y1607263I75J1410D01*
G01D02*
X20731Y1607264D01*
G01D02*
G03X18305Y1608269I-2426J-2426D01*
G01D02*
X18299Y1608263D01*
G01D02*
X12569D01*
G01X322999Y1605549D02*
X21586D01*
G01D02*
G03X20681Y1605174I0J-1280D01*
G01D02*
G02X18648Y1604332I-2033J2033D01*
G01D02*
X18642Y1604326D01*
G01D02*
X12569D01*
G01X28049Y1561050D02*
Y1569550D01*
G01D02*
G03X27123Y1572205I-4269J0D01*
G01X29349Y1561050D02*
Y1569550D01*
G01D02*
G02X30520Y1572049I3252J0D01*
G01X18898Y1557088D02*
X18892Y1557082D01*
G01D02*
X12569D01*
G01X29626Y1645002D02*
G02X30116Y1644007I-1218J-1218D01*
G01D02*
X30218Y1643226D01*
G01D02*
G03X30933Y1641776I2487J325D01*
G01D02*
G03X33224Y1640828I2290J2291D01*
G01D02*
X35000D01*
G01D02*
G03X37098Y1641697I0J2968D01*
G01D02*
X37974Y1642573D01*
G01D02*
X53975Y1658573D01*
G01D02*
X57435Y1662032D01*
G01D02*
G03X58549Y1664719I-2686J2688D01*
G01D02*
Y1813371D01*
G01X33026Y1645051D02*
G03X32128Y1644679I0J-1270D01*
G01D02*
X31853Y1644404D01*
G01D02*
G03X31509Y1643394I853J-854D01*
G01D02*
G03X31853Y1642696I1197J156D01*
G01D02*
G03X33224Y1642128I1371J1371D01*
G01D02*
X34999D01*
G01D02*
G03X36178Y1642617I-1J1668D01*
G01D02*
X37055Y1643493D01*
G01D02*
X53055Y1659493D01*
G01D02*
X56516Y1662953D01*
G01D02*
G03X57249Y1664721I-1767J1768D01*
G01D02*
Y1813372D01*
G01X60949Y1811238D02*
Y1660577D01*
G01D02*
G02X59479Y1657028I-5019J0D01*
G01D02*
X58499Y1656050D01*
G01D02*
X42249Y1639801D01*
G01X18217Y1639765D02*
X18211Y1639759D01*
G01D02*
X12569D01*
G01X62249Y1811237D02*
Y1660581D01*
G01D02*
G02X60398Y1656108I-6325J-2D01*
G01D02*
X59418Y1655130D01*
G01X65949Y1794933D02*
Y1660004D01*
G01D02*
G02X62834Y1652484I-10635J0D01*
G01X62030Y1653519D02*
G03X64649Y1659842I-6323J6323D01*
G01D02*
Y1794934D01*
G01X68349Y1780791D02*
Y1656995D01*
G01D02*
G03X72288Y1646656I15538J0D01*
G01D02*
G03X72900Y1646008I11598J10340D01*
G01D02*
X76805Y1642103D01*
G01X69649Y1738975D02*
Y1714911D01*
G01D02*
G03X70106Y1713996I1115J-15D01*
G01D02*
G02X70564Y1713081I-657J-901D01*
G01D02*
Y1711956D01*
G01D02*
G02X70106Y1711041I-1115J-14D01*
G01D02*
G03X69649Y1710126I658J-900D01*
G01D02*
Y1709001D01*
G01D02*
G03X70106Y1708086I1115J-15D01*
G01D02*
G02X70564Y1707171I-657J-901D01*
G01D02*
Y1706046D01*
G01D02*
G02X70106Y1705131I-1115J-14D01*
G01D02*
G03X69649Y1704216I658J-900D01*
G01D02*
Y1703091D01*
G01D02*
G03X70106Y1702176I1115J-15D01*
G01D02*
G02X70564Y1701261I-657J-901D01*
G01D02*
Y1700136D01*
G01D02*
G02X70106Y1699221I-1115J-14D01*
G01D02*
G03X69649Y1698306I658J-900D01*
G01D02*
Y1689479D01*
G01D02*
G03X70106Y1688564I1115J-15D01*
G01D02*
G02X70564Y1687649I-657J-901D01*
G01D02*
Y1686524D01*
G01D02*
G02X70106Y1685609I-1115J-14D01*
G01D02*
G03X69649Y1684694I658J-900D01*
G01D02*
Y1683569D01*
G01D02*
G03X70106Y1682654I1115J-15D01*
G01D02*
G02X70564Y1681739I-657J-901D01*
G01D02*
Y1680614D01*
G01D02*
G02X70106Y1679699I-1115J-14D01*
G01D02*
G03X69649Y1678784I658J-900D01*
G01D02*
Y1677659D01*
G01D02*
G03X70106Y1676744I1115J-15D01*
G01D02*
G02X70564Y1675829I-657J-901D01*
G01D02*
Y1674704D01*
G01D02*
G02X70106Y1673789I-1115J-14D01*
G01D02*
G03X69649Y1672874I658J-900D01*
G01D02*
Y1656996D01*
G01D02*
G03X73259Y1647522I14236J0D01*
G01D02*
X73262Y1647519D01*
G01D02*
G03X73820Y1646928I10627J9475D01*
G01D02*
X77725Y1643023D01*
G01X51149Y1847652D02*
Y1675786D01*
G01D02*
G02X48816Y1670155I-7962J0D01*
G01D02*
X48605Y1669943D01*
G01D02*
X38605Y1659943D01*
G01D02*
X36049Y1657386D01*
G01D02*
G02X35319Y1656862I-1955J1954D01*
G01D02*
G02X34095Y1656576I-1224J2476D01*
G01D02*
X33209D01*
G01D02*
G02X30521Y1657688I-1J3802D01*
G01D02*
X30433Y1657776D01*
G01D02*
Y1657778D01*
G01D02*
G02X29699Y1659546I1773J1772D01*
G01D02*
G02Y1659579I2693J17D01*
G01D02*
G02X29700Y1659630I2693J-27D01*
G01D02*
G03X29496Y1660143I-697J20D01*
G01D02*
X28600Y1661039D01*
G01X49849Y1847652D02*
Y1675786D01*
G01D02*
G02X47897Y1671075I-6663J1D01*
G01D02*
X47686Y1670863D01*
G01D02*
X35129Y1658306D01*
G01D02*
G02X34743Y1658028I-1037J1033D01*
G01D02*
G02X34700Y1658008I-639J1317D01*
G01D02*
G02X34304Y1657892I-605J1332D01*
G01D02*
G02X34091Y1657876I-216J1448D01*
G01D02*
X33209D01*
G01D02*
G02X31499Y1658552I0J2501D01*
G01D02*
X31353Y1658698D01*
G01D02*
G02X31124Y1659017I853J854D01*
G01D02*
X31123D01*
G01D02*
G02X30999Y1659551I1083J533D01*
G01D02*
G02Y1659568I1393J9D01*
G01D02*
G02X31000Y1659593I1392J-43D01*
G01D02*
G03X30995Y1659809I-1997J62D01*
G01D02*
G02X31179Y1660307I633J49D01*
G01D02*
X31999Y1661127D01*
G01X53549Y1846237D02*
Y1674522D01*
G01D02*
G02X51053Y1668496I-8522J0D01*
G01D02*
X37465Y1654908D01*
G01D02*
G02X35697Y1654176I-1768J1769D01*
G01D02*
X21793D01*
G01D02*
G02X20556Y1654689I1J1750D01*
G01D02*
X20555D01*
G01D02*
G03X18566Y1655513I-1989J-1989D01*
G01D02*
X18560Y1655507D01*
G01D02*
X12569D01*
G01X54849Y1846236D02*
Y1674522D01*
G01D02*
G02X51972Y1667576I-9823J0D01*
G01D02*
X38472Y1654076D01*
G01D02*
G02X35575Y1652876I-2897J2897D01*
G01D02*
X21703D01*
G01D02*
G03X20638Y1652435I0J-1506D01*
G01D02*
G02X18564Y1651576I-2074J2074D01*
G01D02*
X18558Y1651570D01*
G01D02*
X12569D01*
G01Y1671255D02*
X12575Y1671261D01*
G01D02*
X20338D01*
G01D02*
G02X20763Y1671085I0J-601D01*
G01D02*
X21198Y1670650D01*
G01D02*
X21199D01*
G01D02*
G03X21926Y1670349I727J727D01*
G01D02*
X23500D01*
G01D02*
G03X24778Y1670879I-1J1808D01*
G01D02*
X25050Y1671150D01*
G01D02*
X36400Y1682500D01*
G01D02*
G03X37500Y1685156I-2656J2656D01*
G01D02*
Y1728300D01*
G01X38800D02*
Y1685156D01*
G01D02*
G02X37319Y1681580I-5056J-1D01*
G01D02*
X25697Y1669958D01*
G01D02*
G02X23500Y1669050I-2195J2200D01*
G01D02*
Y1669049D01*
G01D02*
X22589D01*
G01D02*
G03X22235Y1669006I1J-1489D01*
G01D02*
G03X21536Y1668613I353J-1446D01*
G01D02*
X20733Y1667810D01*
G01D02*
G02X19560Y1667324I-1173J1173D01*
G01D02*
X12575D01*
G01D02*
X12569Y1667318D01*
G01X29100Y1669500D02*
X29817Y1668783D01*
G01D02*
G02X30100Y1668100I-683J-683D01*
G01D02*
Y1667599D01*
G01D02*
G03X30735Y1666064I2173J0D01*
G01D02*
X30799Y1666000D01*
G01D02*
X30800Y1666001D01*
G01D02*
G03X32734Y1665200I1933J1933D01*
G01D02*
X33799D01*
G01D02*
G03X36768Y1666428I2J4198D01*
G01D02*
X40669Y1670329D01*
G01D02*
Y1670331D01*
G01D02*
G03X42500Y1674752I-4420J4420D01*
G01D02*
Y1724393D01*
G01X32494Y1669706D02*
X31762Y1668974D01*
G01D02*
G03X31400Y1668100I874J-874D01*
G01D02*
Y1667600D01*
G01D02*
G03X31655Y1666984I872J0D01*
G01D02*
X31719Y1666920D01*
G01D02*
G03X32733Y1666500I1014J1014D01*
G01D02*
X33800D01*
G01D02*
G03X35848Y1667348I0J2897D01*
G01D02*
X39750Y1671250D01*
G01D02*
G03X41200Y1674751I-3501J3501D01*
G01D02*
Y1724394D01*
G01X111867Y1777594D02*
X85127Y1804334D01*
G01D02*
G03X80499Y1806251I-4628J-4628D01*
G01X75999Y1806250D02*
G03X71219Y1804270I0J-6760D01*
G01D02*
X68825Y1801876D01*
G01D02*
G03X65949Y1794933I6943J-6943D01*
G01X64649Y1794934D02*
G02X67905Y1802795I11119J-1D01*
G01D02*
X70299Y1805189D01*
G01D02*
G02X75999Y1807550I5700J-5700D01*
G01X86047Y1805254D02*
X112787Y1778514D01*
G01X85630Y1768189D02*
X90234D01*
G01D02*
G02X90557Y1768125I0J-847D01*
G01D02*
X90835Y1768010D01*
G01D02*
G02X91140Y1767706I-215J-521D01*
G01D02*
X91186Y1767594D01*
G01D02*
G02X91229Y1767379I-519J-216D01*
G01D02*
Y1766726D01*
G01D02*
G03X91497Y1766348I401J0D01*
G01D02*
G03X91629Y1766326I131J378D01*
G01D02*
X100794D01*
G01X85630Y1763189D02*
X90400D01*
G01D02*
G03X90970Y1763425I0J806D01*
G01D02*
G03X91101Y1763639I-614J523D01*
G01D02*
X91167Y1763799D01*
G01D02*
G03X91229Y1764108I-743J310D01*
G01D02*
Y1764626D01*
G01D02*
G02X91497Y1765002I398J0D01*
G01D02*
G02X91507Y1765006I153J-367D01*
G01D02*
G02X91563Y1765020I125J-379D01*
G01D02*
G02X91570Y1765021I60J-395D01*
G01D02*
G02X91629Y1765026I63J-395D01*
G01D02*
X101393D01*
G01X77166Y1742559D02*
X81668D01*
G01D02*
X81681Y1742546D01*
G01D02*
G02X82190Y1742335I0J-720D01*
G01D02*
G03X83361Y1741850I1171J1171D01*
G01D02*
X99199D01*
G01X77166Y1739410D02*
X80692D01*
G01D02*
X80705Y1739397D01*
G01D02*
G03X81799Y1739850I0J1547D01*
G01D02*
X82249Y1740300D01*
G01D02*
G02X82853Y1740550I604J-604D01*
G01D02*
X99335D01*
G01X85630Y1778189D02*
X90447D01*
G01D02*
G03X91135Y1778474I0J973D01*
G01D02*
G03X91499Y1779213I-706J807D01*
G01D02*
G02X92536Y1780250I1037J0D01*
G01D02*
X95231D01*
G01X96418Y1788469D02*
X92111Y1792777D01*
G01D02*
G03X87106Y1794850I-5004J-5003D01*
G01D02*
X81499D01*
G01D02*
Y1794849D01*
G01D02*
G03X75457Y1792348I-2J-8543D01*
G01D02*
X71493Y1788384D01*
G01D02*
G03X68349Y1780791I7594J-7592D01*
G01X85630Y1783189D02*
X90758D01*
G01D02*
X90771Y1783176D01*
G01D02*
G02X91799Y1782750I0J-1454D01*
G01D02*
X92823Y1781726D01*
G01D02*
G03X92898Y1781662I426J424D01*
G01D02*
G03X92904Y1781657I387J458D01*
G01D02*
G03X93248Y1781550I342J494D01*
G01D02*
X95240D01*
G01X95498Y1787550D02*
X91191Y1791857D01*
G01D02*
G03X90507Y1792442I-4087J-4086D01*
G01D02*
G03X87106Y1793550I-3402J-4670D01*
G01D02*
X81499D01*
G01D02*
G03X76377Y1791429I-1J-7243D01*
G01D02*
X75999Y1791050D01*
G01D02*
X72413Y1787464D01*
G01D02*
G03X69649Y1780791I6673J-6673D01*
G01D02*
Y1749670D01*
G01D02*
G03X70106Y1748755I1115J-15D01*
G01D02*
G02X70564Y1747840I-657J-901D01*
G01D02*
Y1746715D01*
G01D02*
G02X70106Y1745800I-1115J-14D01*
G01D02*
G03X69649Y1744885I658J-900D01*
G01D02*
Y1743760D01*
G01D02*
G03X70106Y1742845I1115J-15D01*
G01D02*
G02X70564Y1741930I-657J-901D01*
G01D02*
Y1740805D01*
G01D02*
G02X70106Y1739890I-1115J-14D01*
G01D02*
G03X69649Y1738975I658J-900D01*
G01X77166Y1748859D02*
X79950D01*
G01D02*
X79963Y1748846D01*
G01D02*
G03X81293Y1749397I0J1881D01*
G01D02*
X81558Y1749663D01*
G01D02*
G02X82492Y1750050I934J-934D01*
G01D02*
X83499D01*
G01D02*
G02X84800Y1749511I0J-1840D01*
G01D02*
X85084Y1749227D01*
G01D02*
G02X85199Y1748950I-276J-277D01*
G01D02*
Y1748848D01*
G01D02*
G02X85194I-2J102D01*
G01X77166Y1752008D02*
X80724D01*
G01D02*
X80737Y1751995D01*
G01D02*
G02X81701Y1751754I1J-2045D01*
G01D02*
X81829Y1751626D01*
G01D02*
G03X81972Y1751509I665J667D01*
G01D02*
G03X82498Y1751350I526J790D01*
G01D02*
X83180D01*
G01D02*
G03X83744Y1751402I3J3056D01*
G01D02*
G03X85341Y1752245I-564J3004D01*
G01X37500Y1728300D02*
X37501D01*
G01D02*
G02X38941Y1731780I4921J2D01*
G01D02*
X40380Y1733220D01*
G01D02*
G02X42506Y1734100I2126J-2128D01*
G01D02*
X43900D01*
G01D02*
G03X44400Y1734600I0J500D01*
G01D02*
Y1735700D01*
G01D02*
G03X43976Y1736724I-1449J0D01*
G01D02*
X43600Y1737100D01*
G01X47000D02*
X46195Y1736295D01*
G01D02*
G03X45700Y1735100I1195J-1195D01*
G01D02*
Y1734600D01*
G01D02*
G02X43900Y1732800I-1800J0D01*
G01D02*
X42507D01*
G01D02*
G03X41300Y1732300I0J-1707D01*
G01D02*
X39861Y1730860D01*
G01D02*
G03X38800Y1728300I2560J-2561D01*
G01X42500Y1724393D02*
G02X43000Y1725600I1707J0D01*
G01D02*
G02X43966Y1726000I966J-966D01*
G01D02*
X44000D01*
G01D02*
G02X45195Y1725505I0J-1690D01*
G01D02*
X45877Y1724823D01*
G01X41200Y1724394D02*
G02X42080Y1726519I3005J0D01*
G01D02*
G02X43966Y1727300I1886J-1886D01*
G01D02*
X44000D01*
G01D02*
G03X45195Y1727795I0J1690D01*
G01D02*
X45877Y1728477D01*
G01X58549Y1813371D02*
G02X60051Y1816997I5128J0D01*
G01D02*
G02X74400Y1822866I14171J-14171D01*
G01D02*
X127999D01*
G01X57249Y1813372D02*
G02X59131Y1817917I6429J0D01*
G01D02*
G02X74400Y1824166I15090J-15091D01*
G01D02*
X127999D01*
G01X124599Y1820466D02*
X74400D01*
G01D02*
G03X62444Y1815446I0J-16748D01*
G01D02*
G03X60949Y1811238I5176J-4208D01*
G01X124599Y1819166D02*
X74400D01*
G01D02*
G03X63414Y1814576I0J-15442D01*
G01D02*
G03X62249Y1811237I4205J-3340D01*
G01X80499Y1806251D02*
Y1806250D01*
G01D02*
X75999D01*
G01Y1807550D02*
X80342D01*
G01D02*
G02X80499Y1807552I178J-7844D01*
G01D02*
G02X86047Y1805254I0J-7846D01*
G01X99319Y1858371D02*
G03X94783Y1860250I-4536J-4536D01*
G01D02*
X62475D01*
G01D02*
G03X59168Y1858880I0J-4677D01*
G01D02*
X53418Y1853130D01*
G01D02*
G03X51149Y1847652I5478J-5478D01*
G01X100238Y1859291D02*
G03X94784Y1861550I-5455J-5456D01*
G01D02*
X62474D01*
G01D02*
G03X58249Y1859799I2J-5977D01*
G01D02*
X58248D01*
G01D02*
X52499Y1854050D01*
G01D02*
G03X49849Y1847652I6397J-6397D01*
G01X95547Y1853574D02*
G03X88041Y1856683I-7507J-7508D01*
G01D02*
X62841D01*
G01D02*
G03X58616Y1854932I2J-5977D01*
G01D02*
X58615D01*
G01D02*
X56115Y1852432D01*
G01D02*
G03X53549Y1846237I6197J-6196D01*
G01X111615Y1835666D02*
X94628Y1852654D01*
G01D02*
G03X88040Y1855383I-6588J-6588D01*
G01D02*
X62842D01*
G01D02*
G03X59535Y1854013I0J-4677D01*
G01D02*
X57035Y1851513D01*
G01D02*
G03X54849Y1846236I5277J-5277D01*
G01X104249Y145050D02*
G03X106905Y143950I2656J2656D01*
G01D02*
X107610D01*
G01D02*
G03X109000Y145340I0J1390D01*
G01D02*
Y483358D01*
G01X110300D02*
Y145340D01*
G01D02*
G02X107610Y142650I-2690J0D01*
G01D02*
X106905D01*
G01D02*
G03X104249Y141550I0J-3756D01*
G01X108749Y129550D02*
X109999D01*
G01D02*
G02X110994Y129138I0J-1407D01*
G01D02*
X111385Y128747D01*
G01D02*
G03X111544Y128618I715J719D01*
G01D02*
G03X111950Y128450I406J406D01*
G01D02*
X114999D01*
G01D02*
G03X115876Y129327I0J877D01*
G01D02*
Y130050D01*
G01X108749Y126050D02*
X109999D01*
G01D02*
G03X110994Y126462I0J1407D01*
G01D02*
X111458Y126926D01*
G01D02*
G02X111999Y127150I541J-541D01*
G01D02*
X114499D01*
G01D02*
G02X115876Y125973I0J-1394D01*
G01X98885Y144278D02*
G03X100749Y145050I0J2636D01*
G01X97302Y142978D02*
G02X100749Y141550I0J-4875D01*
G01X95899Y119694D02*
G03X99099Y122894I0J3200D01*
G01D02*
Y126350D01*
G01D02*
G02X101299Y128550I2200J0D01*
G01D02*
X103499D01*
G01D02*
G03X104780Y129080I1J1811D01*
G01D02*
X105249Y129550D01*
G01X95899Y118394D02*
G03X100399Y122894I0J4500D01*
G01D02*
Y126350D01*
G01D02*
G02X101299Y127250I900J0D01*
G01D02*
X103774D01*
G01D02*
G02X104243Y127056I0J-664D01*
G01D02*
X105249Y126050D01*
G01X99500Y157978D02*
G03X106000Y164478I0J6500D01*
G01D02*
Y484518D01*
G01X99500Y159278D02*
G03X104700Y164478I0J5200D01*
G01D02*
Y193719D01*
G01D02*
G03X104242Y194634I-1115J14D01*
G01D02*
G02X103785Y195549I658J900D01*
G01D02*
Y196674D01*
G01D02*
G02X104242Y197589I1115J15D01*
G01D02*
G03X104700Y198504I-657J901D01*
G01D02*
Y220544D01*
G01D02*
G03X104242Y221459I-1115J14D01*
G01D02*
G02X103785Y222374I658J900D01*
G01D02*
Y223499D01*
G01D02*
G02X104242Y224414I1115J15D01*
G01D02*
G03X104700Y225329I-657J901D01*
G01D02*
Y226454D01*
G01D02*
G03X104242Y227369I-1115J14D01*
G01D02*
G02X103785Y228284I658J900D01*
G01D02*
Y229409D01*
G01D02*
G02X104242Y230324I1115J15D01*
G01D02*
G03X104700Y231239I-657J901D01*
G01D02*
Y232364D01*
G01D02*
G03X104242Y233279I-1115J14D01*
G01X128249Y224550D02*
G03X125714Y225600I-2535J-2535D01*
G01D02*
X124695D01*
G01D02*
G02X122930Y226331I0J2496D01*
G01D02*
X120481Y228780D01*
G01D02*
G02X117699Y235497I6716J6716D01*
G01X128249Y228050D02*
X127735Y227536D01*
G01D02*
G02X126200Y226900I-1536J1536D01*
G01D02*
X124694D01*
G01D02*
G02X123850Y227251I2J1195D01*
G01D02*
X121401Y229700D01*
G01D02*
G02X119000Y235497I5796J5797D01*
G01X150591Y223937D02*
X145708D01*
G01D02*
G02X144990Y224656I0J718D01*
G01D02*
Y225374D01*
G01D02*
G03X144678Y225763I-399J-1D01*
G01D02*
G03X144590Y225774I-93J-388D01*
G01D02*
X134704D01*
G01D02*
G03X131749Y224550I0J-4179D01*
G01X150591Y228937D02*
X145722D01*
G01D02*
G03X144990Y228206I-1J-731D01*
G01D02*
Y227474D01*
G01D02*
G02X144590Y227074I-400J0D01*
G01D02*
X134105D01*
G01D02*
G02X131749Y228050I0J3332D01*
G01X150591Y213937D02*
X145582D01*
G01D02*
G03X145164Y213764I0J-591D01*
G01D02*
G03X144990Y213344I420J-420D01*
G01D02*
Y212474D01*
G01D02*
G02X144718Y212095I-400J0D01*
G01D02*
G02X144590Y212074I-128J380D01*
G01D02*
X136668D01*
G01D02*
G02X129597Y215003I0J10000D01*
G01D02*
X117729Y226871D01*
G01D02*
G02X114800Y233942I7071J7071D01*
G01X150591Y208937D02*
X145627D01*
G01D02*
G02X145176Y209124I0J637D01*
G01D02*
G02X144990Y209573I449J449D01*
G01D02*
Y210374D01*
G01D02*
G03X144590Y210774I-400J0D01*
G01D02*
X136668D01*
G01D02*
G02X128677Y214083I-1J11300D01*
G01D02*
X116809Y225951D01*
G01D02*
G02X113500Y233942I7991J7990D01*
G01X104242Y233279D02*
G02X103785Y234194I658J900D01*
G01D02*
Y235319D01*
G01D02*
G02X104242Y236234I1115J15D01*
G01D02*
G03X104700Y237149I-657J901D01*
G01D02*
Y322542D01*
G01X117699Y235497D02*
Y480057D01*
G01X119000Y235497D02*
X118999Y235496D01*
G01D02*
Y480057D01*
G01X128249Y249050D02*
G03X127042Y249550I-1207J-1207D01*
G01D02*
X123765D01*
G01D02*
G03X122799Y249150I0J-1366D01*
G01X128249Y252550D02*
X126874Y251175D01*
G01D02*
G02X126089Y250850I-785J785D01*
G01D02*
X123823D01*
G01D02*
G02X123099Y251150I0J1024D01*
G01D02*
X122798Y251451D01*
G01D02*
G02X122397Y252419I968J968D01*
G01D02*
Y252688D01*
G01X159055Y249567D02*
X154497D01*
G01D02*
X154484Y249554D01*
G01D02*
G02X153649Y249900I0J1181D01*
G01D02*
G03X153000Y250169I-649J-649D01*
G01D02*
X134399D01*
G01D02*
G03X134251Y250166I1J-3696D01*
G01D02*
G03X134031Y250150I158J-3692D01*
G01D02*
G03X131786Y249086I368J-3677D01*
G01D02*
X131749Y249050D01*
G01X159055Y252716D02*
X155212D01*
G01D02*
X155199Y252703D01*
G01D02*
G03X154201Y252289I1J-1412D01*
G01D02*
X154130Y252219D01*
G01D02*
X153830Y251919D01*
G01D02*
G02X153557Y251702I-1086J1086D01*
G01D02*
G02X152744Y251469I-813J1303D01*
G01D02*
X132346D01*
G01D02*
G02X131924Y251644I0J596D01*
G01D02*
G02X131749Y252066I421J422D01*
G01D02*
Y252550D01*
G01X114800Y233942D02*
Y481858D01*
G01X113500Y233942D02*
Y481859D01*
G01X159055Y243267D02*
X155105D01*
G01D02*
X155092Y243254D01*
G01D02*
G03X154457Y242991I0J-898D01*
G01D02*
X154157Y242691D01*
G01D02*
G02X153285Y242330I-872J872D01*
G01D02*
X151593D01*
G01D02*
G02X151536Y242331I-11J1014D01*
G01D02*
G02X150876Y242627I58J1013D01*
G01D02*
X149999Y243504D01*
G01X159055Y240118D02*
X155136D01*
G01D02*
X155123Y240105D01*
G01D02*
G02X154437Y240389I0J970D01*
G01D02*
X154218Y240608D01*
G01D02*
G03X153199Y241030I-1019J-1019D01*
G01D02*
X151632D01*
G01D02*
G03X151067Y240796I0J-799D01*
G01D02*
X149999Y239729D01*
G01X104700Y322542D02*
G03X104242Y323457I-1115J14D01*
G01D02*
G02X103785Y324372I658J900D01*
G01D02*
Y325497D01*
G01D02*
G02X104242Y326412I1115J15D01*
G01D02*
G03X104700Y327327I-657J901D01*
G01D02*
Y328452D01*
G01D02*
G03X104242Y329367I-1115J14D01*
G01D02*
G02X103785Y330282I658J900D01*
G01D02*
Y331407D01*
G01D02*
G02X104242Y332322I1115J15D01*
G01D02*
G03X104700Y333237I-657J901D01*
G01D02*
Y334362D01*
G01D02*
G03X104242Y335277I-1115J14D01*
G01D02*
G02X103785Y336192I658J900D01*
G01D02*
Y337317D01*
G01D02*
G02X104242Y338232I1115J15D01*
G01D02*
G03X104700Y339147I-657J901D01*
G01D02*
Y484518D01*
G01X117699Y480057D02*
G02X120628Y487128I10000J0D01*
G01X118999Y480057D02*
G02X121548Y486208I8699J-1D01*
G01X104195Y550988D02*
X104806Y550377D01*
G01D02*
G03X105716Y550000I910J910D01*
G01D02*
X109586D01*
G01D02*
G03X112000Y551000I0J3414D01*
G01D02*
G03X112500Y552207I-1207J1207D01*
G01D02*
Y558343D01*
G01D02*
G03X112042Y559258I-1115J14D01*
G01D02*
G02X111585Y560173I658J900D01*
G01D02*
Y561298D01*
G01D02*
G02X112042Y562213I1115J15D01*
G01D02*
G03X112500Y563128I-657J901D01*
G01D02*
Y564253D01*
G01X113800Y599509D02*
Y552206D01*
G01D02*
G02X112920Y550080I-3008J0D01*
G01D02*
G02X109587Y548700I-3333J3335D01*
G01D02*
X107121D01*
G01D02*
G03X107105Y548699I250J-4130D01*
G01D02*
G03X104195Y547488I15J-4138D01*
G01X104695Y525988D02*
G03X107351Y524888I2656J2656D01*
G01D02*
X108399D01*
G01D02*
G02X109896Y524368I-1J-2417D01*
G01D02*
G02X110108Y524180I-1495J-1899D01*
G01D02*
X110368Y523919D01*
G01D02*
X110649Y523637D01*
G01D02*
X110650D01*
G01D02*
G02X110867Y523394I-2050J-2049D01*
G01D02*
G02X111499Y521587I-2266J-1806D01*
G01D02*
Y520417D01*
G01D02*
G02X110718Y518531I-2666J-1D01*
G01D02*
Y518530D01*
G01D02*
X110418Y518230D01*
G01D02*
G02X109018Y517650I-1400J1400D01*
G01D02*
X101161D01*
G01D02*
G03X98819Y516680I0J-3312D01*
G01D02*
X98418Y516279D01*
G01D02*
G03X97901Y515027I1255J-1251D01*
G01D02*
X97900Y515028D01*
G01D02*
G03X98344Y513956I1516J0D01*
G01D02*
X98900Y513400D01*
G01X104695Y522488D02*
G02X107351Y523588I2656J-2656D01*
G01D02*
X108398D01*
G01D02*
G02X109091Y523347I0J-1117D01*
G01D02*
G02X109189Y523261I-686J-881D01*
G01D02*
X109188Y523260D01*
G01D02*
X109731Y522718D01*
G01D02*
G02X109850Y522584I-1133J-1126D01*
G01D02*
G02X110199Y521588I-1249J-997D01*
G01D02*
Y520416D01*
G01D02*
G02X109799Y519450I-1366J0D01*
G01D02*
X109498Y519149D01*
G01D02*
X109499D01*
G01D02*
G02X109017Y518950I-481J481D01*
G01D02*
X101161D01*
G01D02*
G03X97899Y517599I-1J-4612D01*
G01D02*
X97500Y517200D01*
G01D02*
G03X96600Y515028I2173J-2173D01*
G01D02*
G02X96227Y514126I-1275J-1D01*
G01D02*
X95500Y513400D01*
G01X98277Y549790D02*
G02X98668Y549774I3J-4721D01*
G01D02*
G03X99952Y550245I134J1621D01*
G01D02*
X100695Y550988D01*
G01X98276Y548490D02*
G02X100695Y547488I0J-3421D01*
G01X99655Y525350D02*
G03X101195Y525988I0J2178D01*
G01X97424Y524050D02*
G02X101195Y522488I0J-5333D01*
G01X96523Y563490D02*
G03X98599Y564350I0J2936D01*
G01X109000Y483358D02*
G02X111929Y490429I10000J0D01*
G01D02*
X118371Y496871D01*
G01D02*
G03X121300Y503942I-7071J7071D01*
G01D02*
Y602658D01*
G01X122600D02*
Y503942D01*
G01D02*
G02X119291Y495951I-11300J-1D01*
G01D02*
X112849Y489509D01*
G01D02*
G03X110300Y483358I6150J-6152D01*
G01X106000Y484518D02*
G02X108929Y491589I10000J0D01*
G01D02*
X115170Y497830D01*
G01D02*
G03X118300Y505388I-7559J7558D01*
G01D02*
Y600858D01*
G01X104700Y484518D02*
G02X108009Y492509I11300J1D01*
G01D02*
X114250Y498750D01*
G01D02*
G03X117000Y505389I-6639J6639D01*
G01D02*
Y600858D01*
G01X120628Y487128D02*
X127700Y494200D01*
G01D02*
G03X129700Y499028I-4828J4828D01*
G01D02*
Y606358D01*
G01X121548Y486208D02*
X128620Y493280D01*
G01D02*
G03X131000Y499027I-5749J5747D01*
G01D02*
Y606358D01*
G01X114800Y481858D02*
G02X117349Y488009I8699J-1D01*
G01D02*
X123491Y494151D01*
G01D02*
G03X126800Y502142I-7991J7990D01*
G01D02*
Y604956D01*
G01X113500Y481859D02*
G02X116429Y488929I10000J-1D01*
G01D02*
X122571Y495071D01*
G01D02*
G03X125499Y502142I-7072J7070D01*
G01D02*
X125500Y502141D01*
G01D02*
Y604957D01*
G01X112500Y564253D02*
G03X112042Y565168I-1115J14D01*
G01D02*
G02X111585Y566083I658J900D01*
G01D02*
Y567208D01*
G01D02*
G02X112042Y568123I1115J15D01*
G01D02*
G03X112500Y569038I-657J901D01*
G01D02*
Y570163D01*
G01D02*
G03X112042Y571078I-1115J14D01*
G01D02*
G02X111585Y571993I658J900D01*
G01D02*
Y573118D01*
G01D02*
G02X112042Y574033I1115J15D01*
G01D02*
G03X112500Y574948I-657J901D01*
G01D02*
Y576073D01*
G01D02*
G03X112042Y576988I-1115J14D01*
G01D02*
G02X111585Y577903I658J900D01*
G01D02*
Y579028D01*
G01D02*
G02X112042Y579943I1115J15D01*
G01D02*
G03X112500Y580858I-657J901D01*
G01D02*
Y587689D01*
G01D02*
G03X112042Y588604I-1115J14D01*
G01D02*
G02X111585Y589519I658J900D01*
G01D02*
Y590644D01*
G01D02*
G02X112042Y591559I1115J15D01*
G01D02*
G03X112500Y592474I-657J901D01*
G01D02*
Y593599D01*
G01D02*
G03X112042Y594514I-1115J14D01*
G01D02*
G02X111585Y595429I658J900D01*
G01D02*
Y596554D01*
G01D02*
G02X112042Y597469I1115J15D01*
G01D02*
G03X112500Y598384I-657J901D01*
G01D02*
Y599509D01*
G01D02*
G03X110240Y604961I-7709J-1D01*
G01D02*
X99778Y615422D01*
G01D02*
X95629Y619571D01*
G01X96549Y620491D02*
X100698Y616342D01*
G01D02*
X111160Y605881D01*
G01D02*
G02X113800Y599509I-6370J-6372D01*
G01X98599Y564350D02*
G03X100799Y569661I-5311J5311D01*
G01D02*
Y602061D01*
G01D02*
G03X98270Y608170I-8640J1D01*
G01X96522Y564790D02*
G03X97679Y565270I0J1635D01*
G01D02*
G03X99499Y569662I-4390J4392D01*
G01D02*
Y602061D01*
G01D02*
G03X97350Y607250I-7339J0D01*
G01D02*
X95200Y609400D01*
G01X121300Y602658D02*
G03X118371Y609729I-10000J0D01*
G01D02*
X104409Y623691D01*
G01D02*
G02X101100Y631682I7991J7990D01*
G01D02*
Y723858D01*
G01X102400D02*
Y631682D01*
G01D02*
G03X105329Y624611I10000J0D01*
G01D02*
X119291Y610649D01*
G01D02*
G02X122600Y602658I-7991J-7990D01*
G01X118300Y600858D02*
G03X114991Y608849I-11300J1D01*
G01D02*
X101129Y622711D01*
G01D02*
G02X98200Y629782I7071J7071D01*
G01D02*
Y726158D01*
G01X117000Y600858D02*
G03X114071Y607929I-10000J0D01*
G01D02*
X100209Y621791D01*
G01D02*
G02X96900Y629782I7991J7990D01*
G01D02*
Y726158D01*
G01X122399Y713550D02*
Y638233D01*
G01D02*
G03X122599Y637750I683J0D01*
G01D02*
X122699Y637650D01*
G01D02*
G03X123522Y637432I600J601D01*
G01D02*
G03X124615Y638066I-646J2374D01*
G01D02*
X125499Y638950D01*
G01X121099Y713551D02*
Y638233D01*
G01D02*
G03X121679Y636830I1983J-1D01*
G01D02*
X121780Y636730D01*
G01D02*
G03X123865Y636178I1518J1521D01*
G01D02*
X124368D01*
G01D02*
G02X125227Y635822I0J-1214D01*
G01D02*
X125499Y635550D01*
G01X117399Y717049D02*
Y637441D01*
G01D02*
G03X118715Y634266I4492J2D01*
G01D02*
Y634265D01*
G01D02*
X118714Y634264D01*
G01D02*
X120464Y632514D01*
G01D02*
X120465Y632515D01*
G01D02*
Y632516D01*
G01D02*
G03X123785Y631140I3322J3321D01*
G01D02*
X129093D01*
G01D02*
G02X131688Y630065I0J-3670D01*
G01Y633565D02*
X131669Y633546D01*
G01D02*
G02X128999Y632440I-2670J2670D01*
G01D02*
X123786D01*
G01D02*
G02X121384Y633435I0J3397D01*
G01D02*
X119634Y635185D01*
G01D02*
G02X118699Y637442I2257J2257D01*
G01D02*
Y717050D01*
G01X130595Y647045D02*
G02X131400Y645102I-1943J-1943D01*
G01D02*
Y644600D01*
G01X128657Y646433D02*
G02X128374Y645925I-1033J242D01*
G01D02*
X127999Y645550D01*
G01X150591Y629449D02*
X145465D01*
G01D02*
G02X145100Y629600I0J516D01*
G01D02*
G02X144990Y629866I266J266D01*
G01D02*
Y630886D01*
G01D02*
G03X144719Y631264I-399J0D01*
G01D02*
G03X144590Y631286I-131J-378D01*
G01D02*
X137999D01*
G01D02*
G03X135284Y630162I-1J-3839D01*
G01D02*
X135188Y630065D01*
G01X150591Y634449D02*
X146132D01*
G01D02*
G03X145799Y634383I-1J-869D01*
G01D02*
X145661Y634326D01*
G01D02*
G03X145142Y633806I369J-887D01*
G01D02*
X145032Y633539D01*
G01D02*
G03X144990Y633330I505J-210D01*
G01D02*
Y632986D01*
G01D02*
G02X144677Y632595I-401J0D01*
G01D02*
G02X144666Y632592I-111J384D01*
G01D02*
G02X144590Y632586I-69J395D01*
G01D02*
X137552D01*
G01D02*
G02X135188Y633565I0J3343D01*
G01X150591Y619449D02*
X150571Y619429D01*
G01D02*
X146025D01*
G01D02*
G03X145469Y619269I0J-1046D01*
G01D02*
X145369Y619206D01*
G01D02*
G03X144990Y618520I431J-686D01*
G01D02*
Y617986D01*
G01D02*
G02X144720Y617607I-401J0D01*
G01D02*
G02X144590Y617586I-128J379D01*
G01D02*
X140500D01*
G01D02*
G02X125650Y623737I0J21001D01*
G01D02*
X122544Y626843D01*
G01D02*
Y626844D01*
G01D02*
X116168Y633220D01*
G01D02*
G02X114999Y636042I2822J2822D01*
G01D02*
Y718552D01*
G01X150591Y614449D02*
X150571Y614429D01*
G01D02*
X145536D01*
G01D02*
X145390Y614436D01*
G01D02*
G02X144990Y614836I0J400D01*
G01D02*
Y615886D01*
G01D02*
G03X144701Y616270I-400J0D01*
G01D02*
G03X144590Y616286I-112J-384D01*
G01D02*
X140501D01*
G01D02*
G02X124730Y622817I-2J22302D01*
G01D02*
X122273Y625274D01*
G01D02*
X115248Y632300D01*
G01D02*
X115249Y632301D01*
G01D02*
G02X113699Y636041I3741J3742D01*
G01D02*
Y718551D01*
G01X159055Y645630D02*
X155463D01*
G01D02*
X155450Y645617D01*
G01D02*
G02X154564Y645984I0J1253D01*
G01D02*
G03X153199Y646550I-1366J-1365D01*
G01X145432D02*
G03X144238Y645356I0J-1194D01*
G01X129700Y606358D02*
G03X126771Y613429I-10000J0D01*
G01D02*
X112528Y627672D01*
G01D02*
G02X109599Y634743I7071J7071D01*
G01D02*
Y719557D01*
G01X131000Y606358D02*
G03X127691Y614349I-11300J1D01*
G01D02*
X113828Y628212D01*
G01D02*
G02X110899Y635283I7071J7071D01*
G01D02*
Y719557D01*
G01X126800Y604956D02*
G03X123872Y612027I-10000J1D01*
G01D02*
X116650Y619249D01*
G01D02*
X109429Y626472D01*
G01D02*
G02X106501Y633543I7072J7070D01*
G01D02*
X106500Y633542D01*
G01D02*
Y721258D01*
G01X125500Y604957D02*
X125499Y604956D01*
G01D02*
G03X122952Y611107I-8699J1D01*
G01D02*
X108509Y625552D01*
G01D02*
G02X105200Y633543I7991J7990D01*
G01D02*
Y721258D01*
G01X101100Y723858D02*
G02X104409Y731849I11300J1D01*
G01X105329Y730929D02*
G03X102400Y723858I7071J-7071D01*
G01X98200Y726158D02*
G02X100749Y732309I8699J-1D01*
G01X96900Y726158D02*
G02X99829Y733229I10000J0D01*
G01X145698Y739349D02*
X124167Y717818D01*
G01D02*
G03X122475Y714504I4268J-4268D01*
G01D02*
G03X122399Y713550I5960J-955D01*
G01X145159Y740649D02*
X123247Y718738D01*
G01D02*
G03X121191Y714710I5188J-5187D01*
G01D02*
G03X121099Y713551I7244J-1158D01*
G01X142196Y744587D02*
X125579Y727970D01*
G01D02*
X119334Y721726D01*
G01D02*
G03X117399Y717049I4677J-4674D01*
G01X118699Y717050D02*
G02X120254Y720806I5311J1D01*
G01D02*
X126499Y727050D01*
G01D02*
X143116Y743667D01*
G01X131688Y654565D02*
X131555Y654699D01*
G01D02*
G03X129499Y655550I-2055J-2056D01*
G01D02*
X128770D01*
G01D02*
G03X127517Y655031I0J-1772D01*
G01D02*
G03X126799Y653298I1733J-1733D01*
G01D02*
Y652051D01*
G01D02*
G03X127655Y649987I2917J0D01*
G01D02*
X127795Y649847D01*
G01D02*
X127794Y649846D01*
G01D02*
Y649845D01*
G01D02*
X129931Y647708D01*
G01D02*
X130595Y647045D01*
G01X131688Y658065D02*
X131161Y657539D01*
G01D02*
G02X129499Y656850I-1663J1662D01*
G01D02*
X128771D01*
G01D02*
G03X126598Y655950I-1J-3072D01*
G01D02*
X126597D01*
G01D02*
G03X125499Y653299I2653J-2652D01*
G01D02*
Y652050D01*
G01D02*
G03X126735Y649067I4218J0D01*
G01D02*
X126875Y648927D01*
G01D02*
X126874Y648925D01*
G01D02*
X128374Y647425D01*
G01D02*
G02X128591Y647108I-752J-747D01*
G01D02*
G02X128592Y647105I-1005J-337D01*
G01D02*
G02X128643Y646968I-965J-437D01*
G01D02*
G02X128657Y646433I-1019J-294D01*
G01X159055Y655079D02*
X154996D01*
G01D02*
X154983Y655066D01*
G01D02*
G02X154499Y655550I0J484D01*
G01D02*
G03X154088Y656041I-499J0D01*
G01D02*
G03X153999Y656050I-95J-490D01*
G01D02*
X138773D01*
G01D02*
G03X135188Y654565I0J-5070D01*
G01X159055Y658228D02*
X154877D01*
G01D02*
X154864Y658215D01*
G01D02*
G03X154399Y657750I0J-465D01*
G01D02*
G02X154087Y657359I-401J0D01*
G01D02*
G02X153999Y657350I-84J391D01*
G01D02*
X136914D01*
G01D02*
G02X135188Y658065I0J2441D01*
G01X114999Y718552D02*
G02X116767Y722818I6036J-2D01*
G01D02*
X139603Y745654D01*
G01X113699Y718551D02*
G02X115847Y723738I7337J0D01*
G01D02*
X138683Y746574D01*
G01X159055Y648779D02*
X155858D01*
G01D02*
X155845Y648766D01*
G01D02*
G03X154599Y648250I0J-1762D01*
G01D02*
G02X153633Y647850I-966J966D01*
G01D02*
X145519D01*
G01D02*
G02X144238Y649131I0J1281D01*
G01X153199Y646550D02*
X145432D01*
G01X109599Y719557D02*
G02X112528Y726628I10000J0D01*
G01D02*
X133270Y747370D01*
G01X110899Y719557D02*
G02X113448Y725708I8699J-1D01*
G01D02*
X134190Y746450D01*
G01X106500Y721258D02*
G02X109049Y727409I8699J-1D01*
G01D02*
X130091Y748451D01*
G01X105200Y721258D02*
G02X108129Y728329I10000J0D01*
G01D02*
X129171Y749371D01*
G01X116506Y757306D02*
G03X119900Y765500I-8194J8194D01*
G01D02*
Y991958D01*
G01X121200D02*
Y765501D01*
G01D02*
G02X117426Y756386I-12889J-2D01*
G01D02*
X95920Y734880D01*
G01X114191Y758851D02*
G03X117500Y766842I-7991J7990D01*
G01D02*
Y990357D01*
G01X113271Y759771D02*
G03X116200Y766842I-7071J7071D01*
G01D02*
Y990357D01*
G01X104409Y731849D02*
X125351Y752791D01*
G01D02*
G03X127900Y758942I-6150J6152D01*
G01D02*
Y995658D01*
G01X129200D02*
Y758942D01*
G01D02*
G02X126271Y751871I-10000J0D01*
G01D02*
X105329Y730929D01*
G01X100749Y732309D02*
X120569Y752130D01*
G01D02*
X120570D01*
G01D02*
X121438Y752998D01*
G01D02*
G03X125000Y761599I-8603J8601D01*
G01D02*
Y993758D01*
G01X99829Y733229D02*
X120518Y753918D01*
G01D02*
G03X123700Y761600I-7682J7682D01*
G01D02*
Y993758D01*
G01X148599Y982165D02*
Y752575D01*
G01D02*
X148600Y752574D01*
G01D02*
Y745551D01*
G01D02*
G02X146269Y739919I-7964J-2D01*
G01D02*
X145699Y739349D01*
G01D02*
X145698D01*
G01X147299Y982165D02*
Y752036D01*
G01D02*
X147300Y752035D01*
G01D02*
Y745550D01*
G01D02*
G02X145349Y740839I-6663J0D01*
G01D02*
X145160Y740649D01*
G01D02*
X145159D01*
G01X143599Y1004627D02*
Y750502D01*
G01D02*
X143600Y750501D01*
G01D02*
Y747974D01*
G01D02*
G02X142196Y744587I-4791J1D01*
G01X143116Y743667D02*
G03X144900Y747974I-4307J4307D01*
G01D02*
Y751040D01*
G01D02*
X144899Y751041D01*
G01D02*
Y1004628D01*
G01X139603Y745654D02*
G03X141199Y749507I-3853J3853D01*
G01D02*
Y1002551D01*
G01X138683Y746574D02*
G03X139899Y749507I-2932J2934D01*
G01D02*
Y1002550D01*
G01X133270Y747370D02*
G03X136199Y754441I-7071J7071D01*
G01D02*
Y1001050D01*
G01X134190Y746450D02*
G03X137499Y754441I-7991J7990D01*
G01D02*
Y1001049D01*
G01X130091Y748451D02*
G03X133400Y756442I-7991J7990D01*
G01D02*
Y997758D01*
G01X129171Y749371D02*
G03X132100Y756442I-7071J7071D01*
G01D02*
Y997758D01*
G01X106295Y956489D02*
G03X108951Y955389I2656J2656D01*
G01D02*
G03X112300Y958738I0J3349D01*
G01D02*
Y973721D01*
G01D02*
G03X111842Y974636I-1115J14D01*
G01D02*
G02X111385Y975551I658J900D01*
G01D02*
Y976676D01*
G01D02*
G02X111842Y977591I1115J15D01*
G01X106295Y952989D02*
G02X108885Y954088I2655J-2656D01*
G01D02*
G03X108951I33J5056D01*
G01D02*
G03X113600Y958738I0J4649D01*
G01D02*
Y987799D01*
G01X103295Y931489D02*
X103685Y931099D01*
G01D02*
G03X105399Y930389I1714J1714D01*
G01D02*
X108110D01*
G01D02*
G03X108499Y930550I0J550D01*
G01D02*
G03X108845Y931385I-835J835D01*
G01D02*
Y931657D01*
G01X103295Y927989D02*
X103331Y928026D01*
G01D02*
G02X105532Y929070I2567J-2569D01*
G01D02*
G02X105899Y929089I371J-3612D01*
G01D02*
X107538D01*
G01D02*
G02X108770Y928578I-1J-1743D01*
G01D02*
X109099Y928250D01*
G01X99929Y955302D02*
G03X102795Y956489I0J4053D01*
G01Y952989D02*
G03X100349Y954002I-2446J-2446D01*
G01X95622Y930389D02*
G03X96950Y930939I0J1878D01*
G01D02*
G02X98278Y931489I1328J-1328D01*
G01D02*
X99795D01*
G01X96133Y929089D02*
G02X97461Y928539I0J-1878D01*
G01D02*
G03X98789Y927989I1328J1328D01*
G01D02*
X99795D01*
G01X96399Y969651D02*
G03X97799Y973028I-3380J3380D01*
G01D02*
Y999259D01*
G01X95479Y970570D02*
G03X96499Y973029I-2459J2461D01*
G01D02*
Y999259D01*
G01X111842Y977591D02*
G03X112300Y978506I-657J901D01*
G01D02*
Y979631D01*
G01D02*
G03X111842Y980546I-1115J14D01*
G01D02*
G02X111385Y981461I658J900D01*
G01D02*
Y982586D01*
G01D02*
G02X111842Y983501I1115J15D01*
G01D02*
G03X112300Y984416I-657J901D01*
G01D02*
Y987800D01*
G01D02*
G03X108552Y996848I-12795J0D01*
G01X113600Y987799D02*
G03X109472Y997768I-14096J2D01*
G01X119900Y991958D02*
G03X116971Y999029I-10000J0D01*
G01X117891Y999949D02*
G02X121200Y991958I-7991J-7990D01*
G01X117500Y990357D02*
G03X114191Y998348I-11300J1D01*
G01X116200Y990357D02*
G03X113271Y997428I-10000J0D01*
G01X127900Y995658D02*
G03X124971Y1002729I-10000J0D01*
G01X125891Y1003649D02*
G02X129200Y995658I-7991J-7990D01*
G01X125000Y993758D02*
G03X121691Y1001749I-11300J1D01*
G01X123700Y993758D02*
G03X120771Y1000829I-10000J0D01*
G01X129249Y1035550D02*
G02X125802Y1036978I0J4874D01*
G01D02*
X125541Y1037239D01*
G01D02*
X124931Y1037850D01*
G01D02*
X124803Y1037979D01*
G01D02*
X124615Y1038168D01*
G01D02*
Y1038167D01*
G01X125723Y1038899D02*
X125853Y1038768D01*
G01D02*
G03X128967I1557J1557D01*
G01D02*
X129249Y1039050D01*
G01Y1060050D02*
X128206D01*
G01D02*
G03X126999Y1059550I0J-1707D01*
G01D02*
G03X125999Y1057136I2414J-2414D01*
G01D02*
Y1052550D01*
G01D02*
G02X124099Y1050650I-1900J0D01*
G01D02*
X123999D01*
G01X126073Y1060374D02*
G03X124699Y1057057I3317J-3317D01*
G01D02*
Y1055740D01*
G01D02*
G02X124583Y1055006I-2390J2D01*
G01D02*
G02X124116Y1054176I-2275J733D01*
G01D02*
G02X123999Y1054050I-1809J1562D01*
G01X150591Y1034961D02*
X145708D01*
G01D02*
G02X144990Y1035680I0J718D01*
G01D02*
Y1036398D01*
G01D02*
G03X144718Y1036776I-399J0D01*
G01D02*
G03X144590Y1036798I-131J-378D01*
G01D02*
X135762D01*
G01D02*
G03X134835Y1036696I0J-4261D01*
G01D02*
G03X134546Y1036621I925J-4159D01*
G01D02*
G03X132749Y1035550I1216J-4084D01*
G01X150591Y1039961D02*
X145462D01*
G01D02*
G03X145211Y1039858I0J-357D01*
G01D02*
X145105Y1039753D01*
G01D02*
G03X144990Y1039482I260J-270D01*
G01D02*
Y1038498D01*
G01D02*
G02X144590Y1038098I-400J0D01*
G01D02*
X135762D01*
G01D02*
G03X135497Y1038092I-7J-5561D01*
G01D02*
X135062D01*
G01D02*
G02X134514Y1038138I-1J3271D01*
G01D02*
G02X134303Y1038171I0J690D01*
G01D02*
X134063Y1038248D01*
G01D02*
G02X132749Y1039050I999J3115D01*
G01X133247Y1060547D02*
X132749Y1060050D01*
G01X150591Y1024961D02*
X145813D01*
G01D02*
X145800Y1024948D01*
G01D02*
X145416D01*
G01D02*
G03X145129Y1024829I0J-406D01*
G01D02*
G03X144990Y1024493I337J-336D01*
G01D02*
Y1023498D01*
G01D02*
G02X144718Y1023119I-400J0D01*
G01D02*
G02X144590Y1023098I-128J380D01*
G01D02*
X138999D01*
G01D02*
G02X133521Y1025367I0J7747D01*
G01X150591Y1019961D02*
X145695D01*
G01D02*
G02X145196Y1020168I0J705D01*
G01D02*
G02X144990Y1020665I497J497D01*
G01D02*
Y1021398D01*
G01D02*
G03X144708Y1021779I-399J-1D01*
G01D02*
G03X144590Y1021798I-122J-380D01*
G01D02*
X139000D01*
G01D02*
G02X132601Y1024447I-2J9048D01*
G01X159055Y1054291D02*
X162975D01*
G01D02*
X162988Y1054278D01*
G01D02*
G02X163299Y1054149I0J-440D01*
G01D02*
G02X163649Y1053900I-563J-1162D01*
G01D02*
G03X164494Y1053550I845J845D01*
G01D02*
X166799D01*
G01D02*
G02X169199Y1051150I0J-2400D01*
G01D02*
Y1007503D01*
G01D02*
G02X166899Y1001950I-7855J1D01*
G01D02*
X149649Y984700D01*
G01D02*
G03X148599Y982165I2535J-2535D01*
G01X159055Y1051142D02*
X162609D01*
G01D02*
X162622Y1051129D01*
G01D02*
G03X163469Y1051480I0J1198D01*
G01D02*
X163919Y1051930D01*
G01D02*
G02X164692Y1052250I773J-773D01*
G01D02*
X166799D01*
G01D02*
G02X167899Y1051150I0J-1100D01*
G01D02*
Y1007504D01*
G01D02*
G02X165979Y1002869I-6555J0D01*
G01D02*
X148730Y985620D01*
G01D02*
G03X147299Y982165I3454J-3454D01*
G01X141249Y1010300D02*
G02X143599Y1004627I-5673J-5673D01*
G01X144899Y1004628D02*
G03X142168Y1011219I-9323J-2D01*
G01D02*
X142169Y1011220D01*
G01X141199Y1002551D02*
G03X138274Y1009614I-9990J0D01*
G01X139899Y1002550D02*
G03X137354Y1008694I-8689J0D01*
G01X136199Y1001050D02*
G03X133867Y1006681I-7964J0D01*
G01X137499Y1001049D02*
G03X134787Y1007601I-9265J3D01*
G01X133400Y997758D02*
G03X130091Y1005749I-11300J1D01*
G01D02*
X95610Y1040230D01*
G01X132100Y997758D02*
G03X129171Y1004829I-10000J0D01*
G01X129249Y1063550D02*
X126073Y1060374D01*
G01X159055Y1060591D02*
X155321D01*
G01D02*
X155308Y1060578D01*
G01D02*
G02X154543Y1060895I0J1082D01*
G01D02*
X154293Y1061145D01*
G01D02*
G03X153583Y1061439I-710J-710D01*
G01D02*
X135399D01*
G01D02*
G03X133247Y1060547I1J-3044D01*
G01X159055Y1063740D02*
X155028D01*
G01D02*
X155015Y1063727D01*
G01D02*
G03X154242Y1063407I0J-1093D01*
G01D02*
X153892Y1063057D01*
G01D02*
G02X153124Y1062739I-768J768D01*
G01D02*
X134707D01*
G01D02*
G02X132749Y1063550I0J2769D01*
G01X132700Y1081100D02*
X132774Y1081025D01*
G01D02*
G03X135250Y1080000I2475J2476D01*
G01D02*
X135650D01*
G01D02*
G03X136759Y1080460I-1J1569D01*
G01D02*
X137477Y1081177D01*
G01X132700Y1077600D02*
X132774Y1077675D01*
G01D02*
G02X135250Y1078700I2475J-2476D01*
G01D02*
X135650D01*
G01D02*
G02X136825Y1078214I1J-1661D01*
G01D02*
X137481Y1077557D01*
G01X129200Y1081100D02*
X129019Y1080919D01*
G01D02*
G02X126800Y1080000I-2219J2219D01*
G01D02*
G02X124752Y1080849I1J2897D01*
G01D02*
X124423Y1081177D01*
G01X129200Y1077600D02*
X129019Y1077781D01*
G01D02*
G03X126800Y1078700I-2219J-2219D01*
G01D02*
G03X124752Y1077851I1J-2897D01*
G01D02*
X124423Y1077523D01*
G01X107578Y1361952D02*
X107837D01*
G01D02*
G02X108280Y1361769I1J-626D01*
G01D02*
X108647Y1361402D01*
G01D02*
G03X109975Y1360852I1328J1328D01*
G01D02*
X111314D01*
G01D02*
G03X112999Y1361550I0J2383D01*
G01X107578Y1358452D02*
Y1358540D01*
G01D02*
G02X107641Y1358692I214J0D01*
G01D02*
X108039Y1359090D01*
G01D02*
G02X109154Y1359552I1115J-1114D01*
G01D02*
X110603D01*
G01D02*
G02X112300Y1358849I0J-2400D01*
G01D02*
X112440Y1358709D01*
G01D02*
Y1358196D01*
G01X104078Y1336952D02*
X104598Y1336433D01*
G01D02*
G03X105999Y1335852I1402J1401D01*
G01D02*
X106999D01*
G01D02*
G03X108690Y1336553I-1J2392D01*
G01D02*
X109228Y1337090D01*
G01X104078Y1333452D02*
X104598Y1333971D01*
G01D02*
G02X105999Y1334552I1402J-1401D01*
G01D02*
X106999D01*
G01D02*
G02X108693Y1333851I1J-2395D01*
G01D02*
X109228Y1333315D01*
G01X102135Y1360814D02*
G03X103509Y1361383I0J1943D01*
G01D02*
X104078Y1361952D01*
G01X102265Y1359514D02*
G02X103547Y1358983I0J-1813D01*
G01D02*
X104078Y1358452D01*
G01X98400Y1336050D02*
G03X100578Y1336952I0J3080D01*
G01X98099Y1334750D02*
G02X100115Y1333915I0J-2851D01*
G01D02*
X100578Y1333452D01*
G01X96813Y1373753D02*
X97229Y1373337D01*
G01X96496Y1377097D02*
X97000Y1377600D01*
G01X257111Y1274142D02*
X107602Y1423653D01*
G01X258032Y1275063D02*
X108522Y1424573D01*
G01X253663Y1274195D02*
X105904Y1421955D01*
G01X252743Y1273275D02*
X104984Y1421035D01*
G01X250866Y1269918D02*
X95616Y1425168D01*
G01X251835Y1270788D02*
X96536Y1426087D01*
G01X211991Y1294542D02*
X95826Y1410713D01*
G01X105700Y1348100D02*
X105378Y1347778D01*
G01D02*
G02X103500Y1347000I-1878J1878D01*
G01D02*
G02X102350Y1348150I0J1150D01*
G01D02*
Y1348154D01*
G01X105700Y1344600D02*
X105365Y1344934D01*
G01D02*
G03X104000Y1345500I-1366J-1365D01*
G01D02*
G03X102891Y1345040I1J-1569D01*
G01D02*
X102350Y1344500D01*
G01X109200Y1348100D02*
X109452Y1347849D01*
G01D02*
G03X111500Y1347000I2049J2048D01*
G01D02*
G03X112944Y1347598I0J2042D01*
G01D02*
X113500Y1348154D01*
G01X109200Y1344600D02*
G02X111373Y1345500I2173J-2173D01*
G01D02*
X111500D01*
G01D02*
G02X113207Y1344793I0J-2414D01*
G01D02*
X113500Y1344500D01*
G01X107602Y1423653D02*
X103012Y1428241D01*
G01D02*
G02X100449Y1434429I6190J6189D01*
G01D02*
Y1458970D01*
G01D02*
G03X98829Y1462881I-5531J0D01*
G01X108522Y1424573D02*
X103932Y1429160D01*
G01D02*
G02X101749Y1434430I5270J5270D01*
G01D02*
Y1458971D01*
G01D02*
G03X99749Y1463800I-6831J-1D01*
G01X105904Y1421955D02*
X102854Y1425004D01*
G01D02*
X100977Y1426881D01*
G01D02*
X100976Y1426883D01*
G01D02*
X99904Y1427955D01*
G01D02*
G02X98049Y1432435I4482J4480D01*
G01D02*
Y1455825D01*
G01D02*
G03X95918Y1460970I-7275J1D01*
G01X104984Y1421035D02*
X101934Y1424084D01*
G01D02*
X100055Y1425963D01*
G01D02*
X100054Y1425965D01*
G01D02*
X98984Y1427035D01*
G01D02*
G02X96749Y1432436I5408J5401D01*
G01D02*
Y1455825D01*
G01D02*
G03X94999Y1460050I-5975J0D01*
G01X96536Y1426087D02*
X95960Y1426664D01*
G01D02*
Y1426665D01*
G01D02*
G02X95173Y1427658I3884J3887D01*
G01X95826Y1410713D02*
Y1410714D01*
G01X127640Y1441241D02*
X127474D01*
G01D02*
G02X127191Y1441358I0J401D01*
G01D02*
X126140Y1442409D01*
G01D02*
G03X124799Y1443085I-1696J-1697D01*
G01D02*
G03X124443Y1443112I-359J-2373D01*
G01D02*
X106857D01*
G01D02*
G03X105498Y1442549I0J-1922D01*
G01D02*
X105413Y1442464D01*
G01D02*
G03X104935Y1441310I1154J-1154D01*
G01D02*
Y1440634D01*
G01X127640Y1444741D02*
X127475Y1444576D01*
G01D02*
G02X127078Y1444412I-397J399D01*
G01D02*
X105902D01*
G01D02*
G02X105264Y1444676I0J903D01*
G01D02*
X104999Y1444941D01*
G01X127640Y1465741D02*
X126907Y1466474D01*
G01D02*
G03X125999Y1466850I-908J-908D01*
G01D02*
X125794D01*
G01D02*
G03X124297Y1466230I0J-2117D01*
G01D02*
G03X123808Y1465050I1179J-1180D01*
G01X124290Y1469241D02*
X127640D01*
G01X150591Y1440473D02*
X150578Y1440460D01*
G01D02*
X145924D01*
G01D02*
G02X144999Y1441385I0J925D01*
G01D02*
G03X144334Y1442272I-924J0D01*
G01D02*
G03X144332I-1J-924D01*
G01D02*
G03X144074Y1442310I-262J-886D01*
G01D02*
X132965D01*
G01D02*
G03X131674Y1441775I0J-1825D01*
G01D02*
X131140Y1441241D01*
G01X150591Y1445473D02*
X146502D01*
G01D02*
G03X145277Y1445012I0J-1857D01*
G01D02*
X145140Y1444874D01*
G01D02*
G03X144999Y1444535I337J-339D01*
G01D02*
G02X144074Y1443610I-925J0D01*
G01D02*
X132606D01*
G01D02*
G02X131570Y1444040I1J1466D01*
G01D02*
X131236Y1444373D01*
G01D02*
G02X131140Y1444605I232J232D01*
G01D02*
Y1444741D01*
G01X159055Y1466103D02*
X154302D01*
G01D02*
X154289Y1466090D01*
G01D02*
G02X153550Y1466396I0J1045D01*
G01D02*
G03X152056Y1467015I-1494J-1494D01*
G01D02*
X134216D01*
G01D02*
G03X131140Y1465741I0J-4350D01*
G01X159055Y1469252D02*
X154751D01*
G01D02*
X154738Y1469239D01*
G01D02*
G03X153799Y1468850I0J-1328D01*
G01D02*
G02X152507Y1468315I-1292J1292D01*
G01D02*
X133376D01*
G01D02*
G02X131140Y1469241I0J3162D01*
G01X150591Y1430473D02*
X146785D01*
G01D02*
X146772Y1430460D01*
G01D02*
X146732D01*
G01D02*
G03X144499Y1429535I0J-3158D01*
G01D02*
X143980Y1429017D01*
G01D02*
G02X142999Y1428610I-982J981D01*
G01D02*
X127050D01*
G01D02*
G02X126135Y1429068I-14J1115D01*
G01D02*
G03X125220Y1429525I-900J-658D01*
G01D02*
X124095D01*
G01D02*
G03X123180Y1429068I-15J-1115D01*
G01D02*
G02X122265Y1428610I-901J657D01*
G01D02*
X119283D01*
G01D02*
G02X117945Y1429164I0J1893D01*
G01D02*
X117572Y1429538D01*
G01D02*
G02X117390Y1429976I438J439D01*
G01X150591Y1425473D02*
X147913D01*
G01D02*
X147900Y1425460D01*
G01D02*
X145424D01*
G01D02*
G02X144499Y1426385I0J925D01*
G01D02*
G03X143574Y1427310I-925J0D01*
G01D02*
X119283D01*
G01D02*
G03X117945Y1426756I0J-1893D01*
G01D02*
X117390Y1426201D01*
G01X159055Y1459803D02*
X155035D01*
G01D02*
X155022Y1459790D01*
G01D02*
G03X154129Y1459420I0J-1263D01*
G01D02*
X153879Y1459170D01*
G01D02*
G02X153710Y1459032I-772J773D01*
G01D02*
G02X153106Y1458850I-604J911D01*
G01D02*
X145676D01*
G01D02*
G02X142900Y1460000I0J3926D01*
G01X159055Y1456654D02*
X154896D01*
G01D02*
X154883Y1456641D01*
G01D02*
G02X154436Y1456826I0J632D01*
G01D02*
G02X153994Y1457146I777J1539D01*
G01D02*
G03X153019Y1457550I-975J-975D01*
G01D02*
X145199D01*
G01D02*
G03X143452Y1456827I-1J-2470D01*
G01D02*
X142999Y1456373D01*
G01X107249Y1767550D02*
G03X109012Y1766551I2619J2567D01*
G01D02*
G03X109863Y1766450I853J3553D01*
G01D02*
G03X111631Y1767182I0J2501D01*
G01D02*
X111867Y1767418D01*
G01D02*
G03X112599Y1769186I-1769J1768D01*
G01D02*
Y1775826D01*
G01D02*
G03X111867Y1777594I-2501J0D01*
G01X112787Y1778514D02*
G02X113899Y1775826I-2690J-2687D01*
G01D02*
Y1769186D01*
G01D02*
G02X112787Y1766498I-3802J-1D01*
G01D02*
X112551Y1766262D01*
G01D02*
G02X109863Y1765150I-2687J2690D01*
G01D02*
X109385D01*
G01D02*
G03X107249Y1764050I0J-2624D01*
G01X105249Y1743050D02*
X105395Y1742905D01*
G01D02*
G03X107699Y1741950I2305J2304D01*
G01D02*
G03X108041Y1742091I1J483D01*
G01D02*
X109499Y1743550D01*
G01X105249Y1739550D02*
X105395Y1739695D01*
G01D02*
G02X107699Y1740650I2305J-2304D01*
G01D02*
G02X109079Y1740079I1J-1951D01*
G01D02*
X109399Y1739758D01*
G01D02*
Y1739550D01*
G01X100794Y1766326D02*
G03X103749Y1767550I0J4179D01*
G01X101393Y1765026D02*
G02X103749Y1764050I0J-3332D01*
G01X99199Y1741850D02*
G03X101503Y1742805I-1J3259D01*
G01D02*
X101749Y1743050D01*
G01X99335Y1740550D02*
G02X101749Y1739550I0J-3414D01*
G01X95231Y1780250D02*
G03X96514Y1780586I18J2550D01*
G01D02*
Y1780585D01*
G01D02*
G03X97799Y1782800I-1265J2214D01*
G01D02*
Y1785845D01*
G01D02*
G03X96921Y1787965I-2998J0D01*
G01D02*
X96418Y1788469D01*
G01X95240Y1781550D02*
G03X95869Y1781715I8J1250D01*
G01D02*
X95909Y1781738D01*
G01D02*
G03X96498Y1782800I-661J1061D01*
G01D02*
X96499Y1782799D01*
G01D02*
Y1785846D01*
G01D02*
X96498Y1785845D01*
G01D02*
G03X96001Y1787045I-1697J0D01*
G01D02*
Y1787046D01*
G01D02*
X95498Y1787550D01*
G01X127999Y1822866D02*
Y1822867D01*
G01D02*
G02X130021Y1822029I-1J-2861D01*
G01D02*
X130498Y1821551D01*
G01D02*
X130804Y1821245D01*
G01D02*
G03X134896Y1819550I4092J4092D01*
G01D02*
X134897Y1819549D01*
G01D02*
X134898Y1819550D01*
G01D02*
X264482D01*
G01X127999Y1824166D02*
G02X130941Y1822948I1J-4160D01*
G01D02*
X131418Y1822470D01*
G01D02*
X131723Y1822165D01*
G01D02*
G03X134897Y1820850I3174J3172D01*
G01D02*
X264481D01*
G01X258261Y1808550D02*
X142931D01*
G01D02*
G02X136796Y1811092I0J8675D01*
G01D02*
X129418Y1818470D01*
G01D02*
G03X124599Y1820466I-4819J-4819D01*
G01X258262Y1807250D02*
X142930D01*
G01D02*
G02X135876Y1810172I0J9976D01*
G01D02*
X128498Y1817550D01*
G01D02*
G03X124599Y1819166I-3900J-3898D01*
G01X128342Y1846254D02*
G03X125986Y1847230I-2356J-2356D01*
G01D02*
X113843D01*
G01D02*
G02X108070Y1849621I-1J8163D01*
G01D02*
X108069Y1849620D01*
G01D02*
X99319Y1858371D01*
G01X128342Y1849754D02*
X128263Y1849675D01*
G01D02*
G02X125499Y1848530I-2764J2764D01*
G01D02*
X113842D01*
G01D02*
G02X108989Y1850540I0J6863D01*
G01D02*
X100238Y1859291D01*
G01X128342Y1870754D02*
X128299Y1870798D01*
G01D02*
G03X125999Y1871750I-2299J-2300D01*
G01D02*
X124999D01*
G01D02*
G03X123779Y1871244I1J-1726D01*
G01D02*
X123393Y1870859D01*
G01X128342Y1874254D02*
X128121Y1874033D01*
G01D02*
G02X125999Y1873154I-2122J2122D01*
G01D02*
X125299D01*
G01D02*
G02X124263Y1873583I0J1465D01*
G01D02*
X123592Y1874254D01*
G01X150591Y1845985D02*
X145716D01*
G01D02*
G02X145203Y1846197I0J727D01*
G01D02*
G02X144990Y1846711I514J514D01*
G01D02*
Y1847422D01*
G01D02*
G03X144590Y1847822I-400J0D01*
G01D02*
X135627D01*
G01D02*
G03X131842Y1846254I0J-5353D01*
G01X150591Y1850985D02*
X145911D01*
G01D02*
G03X145016Y1850328I-1J-937D01*
G01D02*
X144999Y1850275D01*
G01D02*
G03X144990Y1850212I204J-61D01*
G01D02*
Y1849522D01*
G01D02*
G02X144709Y1849140I-400J0D01*
G01D02*
G02X144590Y1849122I-119J382D01*
G01D02*
X133368D01*
G01D02*
G02X131842Y1849754I0J2158D01*
G01X159055Y1871615D02*
X155277D01*
G01D02*
X155264Y1871602D01*
G01D02*
G02X154335Y1871987I0J1314D01*
G01D02*
G03X153034Y1872526I-1301J-1301D01*
G01D02*
X135599D01*
G01D02*
G03X135129Y1872502I9J-4791D01*
G01D02*
G03X132211Y1871122I470J-4768D01*
G01D02*
X131842Y1870754D01*
G01X159055Y1874764D02*
X155175D01*
G01D02*
X155162Y1874751D01*
G01D02*
G03X154409Y1874439I0J-1065D01*
G01D02*
X154109Y1874139D01*
G01D02*
G02X153353Y1873826I-756J756D01*
G01D02*
X132875D01*
G01D02*
G02X131842Y1874254I0J1461D01*
G01X150591Y1835985D02*
X146354D01*
G01D02*
G03X144700Y1835300I0J-2339D01*
G01D02*
X144441Y1835042D01*
G01D02*
G03X144300Y1834700I342J-341D01*
G01D02*
Y1834622D01*
G01D02*
G02X143800Y1834122I-500J0D01*
G01D02*
X118484D01*
G01D02*
G02X112535Y1836586I0J8413D01*
G01D02*
X95547Y1853574D01*
G01X150591Y1830985D02*
X146048D01*
G01D02*
G02X144797Y1831503I0J1770D01*
G01D02*
G02X144499Y1832222I718J719D01*
G01D02*
G03X144091Y1832789I-598J0D01*
G01D02*
G03X143899Y1832822I-192J-542D01*
G01D02*
X118485D01*
G01D02*
G02X111616Y1835667I-1J9713D01*
G01D02*
X111615Y1835666D01*
G01X159055Y1865315D02*
X155211D01*
G01D02*
X155198Y1865302D01*
G01D02*
G03X154384Y1864965I0J-1151D01*
G01D02*
X154184Y1864765D01*
G01D02*
G02X153247Y1864377I-937J937D01*
G01D02*
X141296D01*
G01D02*
G03X141196Y1864376I5J-5452D01*
G01D02*
G03X139560Y1864093I101J-5452D01*
G01D02*
G02X138903Y1864247I-204J608D01*
G01D02*
X137999Y1865151D01*
G01X159055Y1862166D02*
X155524D01*
G01D02*
X155511Y1862153D01*
G01D02*
G02X154161Y1862712I0J1909D01*
G01D02*
G03X153280Y1863077I-881J-881D01*
G01D02*
X141299D01*
G01D02*
G03X141222Y1863076I15J-4152D01*
G01D02*
G03X138363Y1861861I77J-4152D01*
G01D02*
X137999Y1861497D01*
G01X326370Y1088959D02*
X216456Y1293223D01*
G01X217719Y1293622D02*
X327516Y1089575D01*
G01X323756Y1087804D02*
X214286Y1291427D01*
G01X322610Y1087188D02*
X213140Y1290811D01*
G01X837846Y1037762D02*
X260462Y1271989D01*
G01D02*
G02X257111Y1274142I4055J9995D01*
G01X260918Y1273207D02*
G02X258032Y1275063I2829J7571D01*
G01X858139Y1023450D02*
X260310Y1268526D01*
G01D02*
G02X256810Y1271048I6015J12037D01*
G01D02*
X253663Y1274195D01*
G01X857646Y1022247D02*
X259947Y1267269D01*
G01D02*
G02X259729Y1267363I724J1978D01*
G01D02*
G02X255891Y1270129I6597J13199D01*
G01D02*
X255889Y1270127D01*
G01D02*
X252743Y1273275D01*
G01X414666Y1066619D02*
X250879Y1269902D01*
G01D02*
G03X250874Y1269908I-291J-237D01*
G01D02*
X250866Y1269918D01*
G01X415678Y1067435D02*
X251835Y1270788D01*
G01X261634Y1250669D02*
X240321Y1277068D01*
G01X409959Y1064871D02*
X239352Y1276197D01*
G01X216456Y1293223D02*
G03X215718Y1294216I-3738J-2007D01*
G01D02*
X214747Y1295187D01*
G01D02*
X214569Y1295366D01*
G01X215490Y1296284D02*
X215668Y1296105D01*
G01D02*
X216111Y1295663D01*
G01D02*
X216638Y1295136D01*
G01D02*
G02X217601Y1293839I-3922J-3918D01*
G01D02*
X217717Y1293624D01*
G01D02*
X217719Y1293622D01*
G01X214286Y1291427D02*
X214287D01*
G01D02*
X214132Y1291714D01*
G01D02*
X214131D01*
G01D02*
G03X212018Y1294517I-10077J-5398D01*
G01D02*
G03X211991Y1294542I-338J-339D01*
G01X213140Y1290811D02*
X212985Y1291100D01*
G01D02*
G03X211071Y1293622I-8928J-4788D01*
G01D02*
X210346Y1294347D01*
G01X264920Y1811309D02*
G02X258261Y1808550I-6659J6657D01*
G01X265840Y1810389D02*
G02X258262Y1807250I-7578J7578D01*
G01X769378Y265673D02*
X326370Y1088959D01*
G01X766259Y264716D02*
X323756Y1087804D01*
G01X765114Y264100D02*
X322610Y1087188D01*
G01X327516Y1089575D02*
X770525Y266290D01*
G01X410972Y1065689D02*
X261634Y1250669D01*
G01X838335Y1038967D02*
X260918Y1273207D01*
G01X798279Y1451954D02*
X327885Y1608910D01*
G01D02*
G03X324948Y1609408I-3385J-11053D01*
G01D02*
G03X324499Y1609417I-456J-11551D01*
G01X798690Y1453188D02*
X328287Y1610148D01*
G01D02*
G03X324999Y1610707I-3799J-12397D01*
G01D02*
G03X324500Y1610717I-507J-12850D01*
G01X734728Y1467421D02*
X327305Y1606139D01*
G01D02*
G03X327175Y1606183I-2274J-6505D01*
G01D02*
G03X322999Y1606849I-4175J-12752D01*
G01X734308Y1466189D02*
X326771Y1604947D01*
G01D02*
G03X322999Y1605549I-3772J-11516D01*
G01X264482Y1819550D02*
G03X269157Y1820646I0J10518D01*
G01D02*
G03X271919Y1822630I-4675J9422D01*
G01D02*
X283574Y1834284D01*
G01D02*
G02X289000Y1836533I5427J-5424D01*
G01D02*
X829300D01*
G01X264481Y1820850D02*
G03X268579Y1821811I0J9218D01*
G01D02*
G03X270999Y1823550I-4098J8257D01*
G01D02*
X282654Y1835204D01*
G01D02*
G02X288999Y1837833I6346J-6345D01*
G01D02*
X829300D01*
G01X871582Y1834133D02*
X293356D01*
G01D02*
G03X292961Y1834127I8J-13549D01*
G01D02*
X292463D01*
G01D02*
G03X284397Y1830786I0J-11407D01*
G01D02*
X264922Y1811311D01*
G01D02*
G02X264920Y1811309I-6664J6662D01*
G01X871216Y1832833D02*
X292480D01*
G01D02*
G03X285317Y1829866I0J-10130D01*
G01D02*
X265842Y1810391D01*
G01D02*
G02X265840Y1810389I-7584J7582D01*
G01X761743Y635849D02*
X414666Y1066619D01*
G01X762713Y636718D02*
X415678Y1067435D01*
G01X771727Y618836D02*
X410972Y1065689D01*
G01X770761Y617961D02*
X409959Y1064871D01*
G01X794226Y1447163D02*
X734728Y1467421D01*
G01X793806Y1445931D02*
X734308Y1466189D01*
G01X841399Y228354D02*
X773381Y261431D01*
G01X773693Y262725D02*
X841950Y229532D01*
G01X869979Y212832D02*
X836007Y227247D01*
G01D02*
G02X773066Y257733I274964J647904D01*
G01X869147Y211770D02*
X835499Y226050D01*
G01D02*
G02X772441Y256593I275474J649100D01*
G01X773381Y261431D02*
G02X769378Y265673I5884J9562D01*
G01X770525Y266290D02*
X770526Y266287D01*
G01D02*
X770623Y266107D01*
G01D02*
G03X773693Y262725I8362J4506D01*
G01X773066Y257733D02*
X773075Y257728D01*
G01D02*
G02X766259Y264716I8757J15359D01*
G01X772441Y256593D02*
G02X765114Y264100I9391J16495D01*
G01X852999Y631482D02*
X772214D01*
G01D02*
G02X761743Y635849I1J14738D01*
G01X852999Y632782D02*
X772215D01*
G01D02*
G02X762713Y636718I0J13438D01*
G01X872074Y617586D02*
X775141D01*
G01D02*
X775085Y617594D01*
G01D02*
X774786D01*
G01D02*
G02X771727Y618836I1J4390D01*
G01X872264Y616286D02*
X775006D01*
G01D02*
X774999Y616293D01*
G01D02*
X774992Y616294D01*
G01D02*
X774785D01*
G01D02*
G02X770761Y617961I0J5691D01*
G01X842366Y1036993D02*
G02X837847Y1037763I-513J10635D01*
G01D02*
X837846Y1037762D01*
G01X842303Y1038292D02*
G02X838335Y1038967I-453J9336D01*
G01X854144Y1441896D02*
X830499D01*
G01D02*
G02X826783Y1442443I0J12896D01*
G01D02*
X798279Y1451954D01*
G01X854144Y1443196D02*
X830499D01*
G01D02*
G02X827206Y1443674I0J11582D01*
G01D02*
X798690Y1453188D01*
G01X847583Y1428996D02*
X794226Y1447163D01*
G01X847257Y1427733D02*
X793806Y1445931D01*
G01X829300Y1836533D02*
Y1836534D01*
G01D02*
G03X835569Y1839128I3J8864D01*
G01D02*
X840519Y1844080D01*
G01X829300Y1837833D02*
G03X834649Y1840048I1J7564D01*
G01D02*
X839600Y1845000D01*
G01D02*
X841328Y1846728D01*
G01X855728Y224924D02*
X854018Y225297D01*
G01D02*
G02X852878Y225712I965J4423D01*
G01D02*
X852486Y225918D01*
G01D02*
G03X852167Y226010I-386J-740D01*
G01D02*
X851999Y226024D01*
G01D02*
X851083D01*
G01D02*
G02X850916Y226039I-2J914D01*
G01D02*
X845724Y227007D01*
G01D02*
G02X845474Y227056I373J2568D01*
G01D02*
G02X842305Y227933I14452J58384D01*
G01D02*
X842304Y227932D01*
G01D02*
X842208Y227962D01*
G01D02*
X841419Y228345D01*
G01D02*
X841399Y228354D01*
G01X841950Y229532D02*
X841970Y229523D01*
G01D02*
X842685Y229176D01*
G01D02*
G03X845787Y228318I17233J56266D01*
G01D02*
X851120Y227324D01*
G01D02*
X852287D01*
G01D02*
G03X853709Y227913I0J2011D01*
G01D02*
G02X854943Y228424I1234J-1234D01*
G01D02*
X855728D01*
G01X859228Y224924D02*
X860146D01*
G01D02*
G03X861474Y225474I0J1878D01*
G01D02*
G02X862802Y226024I1328J-1328D01*
G01D02*
X872031D01*
G01D02*
G02X872876Y225674I0J-1195D01*
G01D02*
G02X873032Y225484I-556J-616D01*
G01D02*
X873075Y225412D01*
G01D02*
G02X873247Y225069I-2287J-1362D01*
G01D02*
X873320Y224892D01*
G01D02*
G03X873547Y224553I968J402D01*
G01D02*
X873600Y224500D01*
G01D02*
G03X874959Y223937I1359J1359D01*
G01D02*
X878937D01*
G01Y228937D02*
X874984D01*
G01D02*
G03X874050Y228550I0J-1321D01*
G01D02*
X873410Y227910D01*
G01D02*
G02X872665Y227438I-1416J1411D01*
G01D02*
G02X872624Y227424I-667J1885D01*
G01D02*
G02X872591Y227414I-596J1908D01*
G01D02*
G02X872524Y227394I-605J1906D01*
G01D02*
G02X872240Y227338I-528J1929D01*
G01D02*
G02X872001Y227323I-245J1985D01*
G01D02*
G02X871996Y227324I390J1962D01*
G01D02*
X863378D01*
G01D02*
G02X862050Y227874I0J1878D01*
G01D02*
G03X860722Y228424I-1328J-1328D01*
G01D02*
X859228D01*
G01X878937Y213937D02*
X874867D01*
G01D02*
G03X873192Y213244I-1J-2368D01*
G01D02*
X872499Y212550D01*
G01D02*
X872371Y212421D01*
G01D02*
G02X872184Y212277I-633J628D01*
G01D02*
G02X872155Y212261I-445J772D01*
G01D02*
G02X872040Y212211I-412J790D01*
G01D02*
G02X872023Y212205I-305J837D01*
G01D02*
G02X871733Y212159I-283J846D01*
G01D02*
G02X871392Y212231I10J891D01*
G01D02*
X871336Y212255D01*
G01D02*
X871318Y212263D01*
G01D02*
X871195Y212315D01*
G01D02*
X871191Y212317D01*
G01D02*
X870585Y212573D01*
G01D02*
X870032Y212808D01*
G01D02*
X870029Y212809D01*
G01D02*
X870025Y212811D01*
G01D02*
X870022Y212812D01*
G01D02*
X870008Y212819D01*
G01D02*
X869996Y212824D01*
G01D02*
X869993Y212825D01*
G01D02*
X869987Y212828D01*
G01D02*
X869979Y212831D01*
G01D02*
Y212832D01*
G01X878937Y208937D02*
X874059D01*
G01D02*
G02X872700Y209500I0J1922D01*
G01D02*
X872596Y209604D01*
G01D02*
G02X872429Y210007I404J404D01*
G01D02*
G03X872262Y210411I-571J1D01*
G01D02*
G03X871680Y210695I-2948J-5304D01*
G01D02*
X870827Y211057D01*
G01D02*
X870809Y211065D01*
G01D02*
X870686Y211117D01*
G01D02*
X870682Y211119D01*
G01D02*
X869147Y211770D01*
G01X855728Y249424D02*
G03X854400Y249974I-1328J-1328D01*
G01D02*
X851278D01*
G01X855728Y252924D02*
X854841D01*
G01D02*
G03X847878Y250040I0J-9847D01*
G01X887401Y249567D02*
X883522D01*
G01D02*
X883509Y249554D01*
G01D02*
G02X882826Y249837I0J966D01*
G01D02*
G02X882585Y250036I923J1363D01*
G01D02*
G03X881651Y250423I-934J-934D01*
G01D02*
X861640D01*
G01D02*
G03X859228Y249424I0J-3411D01*
G01X887401Y252716D02*
X883612D01*
G01D02*
X883599Y252703D01*
G01D02*
G03X882689Y252326I0J-1287D01*
G01D02*
X882501Y252138D01*
G01D02*
G02X881499Y251723I-1002J1002D01*
G01D02*
X861999D01*
G01D02*
G02X861850Y251725I-24J3791D01*
G01D02*
G02X859319Y252833I150J3788D01*
G01D02*
X859228Y252924D01*
G01X887401Y243267D02*
X883311D01*
G01D02*
X883298Y243254D01*
G01D02*
G03X882900Y243089I0J-563D01*
G01D02*
X882381Y242568D01*
G01D02*
G02X881805Y242330I-575J576D01*
G01D02*
X880399D01*
G01D02*
X880230Y242334D01*
G01D02*
G02X879192Y242764I0J1468D01*
G01D02*
X878078Y243878D01*
G01X887401Y240118D02*
X883512D01*
G01D02*
X883499Y240105D01*
G01D02*
G02X882761Y240410I-1J1043D01*
G01D02*
X882760Y240412D01*
G01D02*
X882325Y240848D01*
G01D02*
G03X881886Y241030I-439J-439D01*
G01D02*
X880199D01*
G01D02*
G03X878160Y240186I-1J-2883D01*
G01D02*
X878078Y240103D01*
G01X855946Y630382D02*
G03X852999Y631482I-2947J-3398D01*
G01X855946Y633882D02*
G02X852999Y632782I-2947J3398D01*
G01X878937Y629449D02*
X873574D01*
G01D02*
G02X873443Y629475I-1J340D01*
G01D02*
X873376Y629503D01*
G01D02*
G02X872832Y630317I337J814D01*
G01D02*
Y630402D01*
G01D02*
G03X872573Y631027I-884J0D01*
G01D02*
G03X871948Y631286I-625J-625D01*
G01D02*
X861499D01*
G01D02*
G03X859446Y630382I0J-2783D01*
G01X878937Y634449D02*
X873438D01*
G01D02*
G03X872774Y634174I0J-939D01*
G01D02*
X872636Y634036D01*
G01D02*
G03X872499Y633705I331J-331D01*
G01D02*
Y633511D01*
G01D02*
G02X872076Y632734I-925J0D01*
G01D02*
G02X872041Y632712I-510J772D01*
G01D02*
G02X871574Y632586I-466J800D01*
G01D02*
X861499D01*
G01D02*
G02X859446Y633882I0J2274D01*
G01X878937Y619449D02*
X873938D01*
G01D02*
G03X873274Y619174I0J-939D01*
G01D02*
X873136Y619036D01*
G01D02*
G03X872999Y618705I331J-331D01*
G01D02*
Y618511D01*
G01D02*
G02X872084Y617586I-925J0D01*
G01D02*
G02X872074I-5J925D01*
G01X878937Y614449D02*
X873871D01*
G01D02*
G02X873664Y614482I1J675D01*
G01D02*
X873499Y614535D01*
G01D02*
G02X873107Y615075I176J540D01*
G01D02*
Y615444D01*
G01D02*
G03X872860Y616039I-841J0D01*
G01D02*
G03X872264Y616286I-596J-596D01*
G01X887401Y645630D02*
X884328D01*
G01D02*
X884315Y645617D01*
G01D02*
G02X883149Y646100I0J1649D01*
G01D02*
X882849Y646400D01*
G01X879436Y646413D02*
X878596Y645573D01*
G01X855946Y654882D02*
X855261Y655567D01*
G01D02*
G03X854199Y656007I-1062J-1062D01*
G01D02*
X852560D01*
G01D02*
G03X851172Y655432I0J-1963D01*
G01X855946Y658382D02*
X855417Y657853D01*
G01D02*
G02X854099Y657307I-1318J1318D01*
G01D02*
X850676D01*
G01D02*
G03X849025Y656623I0J-2335D01*
G01D02*
X847772Y655370D01*
G01X887401Y655079D02*
X884622D01*
G01D02*
X884609Y655066D01*
G01D02*
G02X883199Y655650I0J1994D01*
G01D02*
G03X882233Y656050I-966J-966D01*
G01D02*
X861899D01*
G01D02*
G03X859706Y655141I1J-3102D01*
G01D02*
X859446Y654882D01*
G01X887401Y658228D02*
X884165D01*
G01D02*
X884152Y658215D01*
G01D02*
G03X882880Y657688I0J-1799D01*
G01D02*
G03X882766Y657582I1414J-1635D01*
G01D02*
G02X882534Y657421I-560J560D01*
G01D02*
G02X882206Y657350I-328J721D01*
G01D02*
X861899D01*
G01D02*
G02X859473Y658355I0J3431D01*
G01D02*
X859446Y658382D01*
G01X887401Y648779D02*
X883816D01*
G01D02*
X883803Y648766D01*
G01D02*
G03X882799Y648350I0J-1420D01*
G01D02*
G02X882075Y648050I-724J724D01*
G01D02*
X880457D01*
G01D02*
G02X880376Y648052I-7J1359D01*
G01D02*
G02X879496Y648448I81J1357D01*
G01D02*
X878596Y649348D01*
G01X882849Y646400D02*
G03X882004Y646750I-845J-845D01*
G01D02*
X880250D01*
G01D02*
G03X879436Y646413I0J-1151D01*
G01X855583Y1035892D02*
G03X851881Y1036953I-4583J-9002D01*
G01D02*
G03X850999Y1036992I-887J-10062D01*
G01D02*
X842366D01*
G01D02*
Y1036993D01*
G01X855583Y1039392D02*
G02X851999Y1038292I-3584J5289D01*
G01D02*
X842303D01*
G01X878937Y1034961D02*
X878917Y1034941D01*
G01D02*
X875095D01*
G01D02*
G02X873327Y1035673I0J2501D01*
G01D02*
X872594Y1036406D01*
G01D02*
G03X871180Y1036992I-1414J-1413D01*
G01D02*
X862770D01*
G01D02*
G03X861442Y1036442I0J-1878D01*
G01D02*
G02X860114Y1035892I-1328J1328D01*
G01D02*
X859083D01*
G01X878937Y1039961D02*
X874252D01*
G01D02*
X874232Y1039941D01*
G01D02*
G03X872949Y1039410I0J-1815D01*
G01D02*
X872417Y1038878D01*
G01D02*
G02X871003Y1038292I-1414J1413D01*
G01D02*
X862986D01*
G01D02*
G02X861658Y1038842I0J1878D01*
G01D02*
G03X860330Y1039392I-1328J-1328D01*
G01D02*
X859083D01*
G01X878937Y1024961D02*
X873669D01*
G01D02*
G03X873314Y1024814I0J-502D01*
G01D02*
X873167Y1024667D01*
G01D02*
G03X872999Y1024261I407J-406D01*
G01D02*
Y1024023D01*
G01D02*
G02X872402Y1023158I-925J0D01*
G01D02*
G02X872334Y1023135I-330J864D01*
G01D02*
G02X872074Y1023098I-259J888D01*
G01D02*
X860396D01*
G01D02*
X860351Y1023095D01*
G01D02*
G02X858138Y1023449I-350J4907D01*
G01D02*
X858139Y1023450D01*
G01X878937Y1019961D02*
X878910Y1019988D01*
G01D02*
X873694D01*
G01D02*
G02X873212Y1020188I0J681D01*
G01D02*
X873079Y1020321D01*
G01D02*
G02X872972Y1020471I388J390D01*
G01D02*
X872932Y1020555D01*
G01D02*
G02X872900Y1020698I300J142D01*
G01D02*
G03X872324Y1021665I-1100J0D01*
G01D02*
G03X871800Y1021798I-524J-966D01*
G01D02*
X860442D01*
G01D02*
G02X857646Y1022247I-438J6203D01*
G01X887401Y1054291D02*
X884275D01*
G01D02*
X884262Y1054278D01*
G01D02*
G03X883349Y1053900I0J-1291D01*
G01D02*
X883149Y1053700D01*
G01D02*
X882748Y1053300D01*
G01D02*
G02X882216Y1053079I-533J532D01*
G01D02*
G02X882017Y1053052I-283J1337D01*
G01D02*
G02X881933Y1053050I-75J1364D01*
G01D02*
X880899D01*
G01D02*
G02X878339Y1054111I1J3621D01*
G01D02*
X877964Y1054485D01*
G01X887401Y1051142D02*
X884371D01*
G01D02*
X884358Y1051129D01*
G01D02*
G02X883651Y1051422I0J1000D01*
G01D02*
G02X883475Y1051573I896J1223D01*
G01D02*
G03X883048Y1051750I-427J-427D01*
G01D02*
X879814D01*
G01D02*
G03X878233Y1051095I0J-2236D01*
G01X855583Y1060892D02*
X855320Y1061155D01*
G01D02*
G03X853299Y1061992I-2021J-2021D01*
G01D02*
X851384D01*
G01D02*
G03X850833Y1061441I0J-551D01*
G01X855583Y1064392D02*
X855108Y1063917D01*
G01D02*
G02X853599Y1063292I-1509J1509D01*
G01D02*
X850399D01*
G01D02*
G03X848067Y1062326I0J-3298D01*
G01D02*
X847233Y1061492D01*
G01X887401Y1060591D02*
X883533D01*
G01D02*
X883520Y1060578D01*
G01D02*
G02X882747Y1060898I0J1093D01*
G01D02*
X882447Y1061198D01*
G01D02*
G03X881711Y1061503I-736J-736D01*
G01D02*
X860558D01*
G01D02*
G03X859083Y1060892I0J-2086D01*
G01X887401Y1063740D02*
X883732D01*
G01D02*
X883719Y1063727D01*
G01D02*
G03X882604Y1063265I0J-1577D01*
G01D02*
G02X881489Y1062803I-1115J1114D01*
G01D02*
X862919D01*
G01D02*
G02X859083Y1064392I0J5425D01*
G01X857077Y1440796D02*
G03X854144Y1441896I-2933J-3360D01*
G01X857077Y1444296D02*
G02X854144Y1443196I-2933J3360D01*
G01X857077Y1465796D02*
X856908Y1465964D01*
G01D02*
G03X854599Y1466921I-2310J-2309D01*
G01D02*
X853676D01*
G01D02*
G03X852288Y1466346I0J-1963D01*
G01X857077Y1469296D02*
X856994Y1469213D01*
G01D02*
G02X854599Y1468221I-2395J2395D01*
G01D02*
X852799D01*
G01D02*
G03X849227Y1466742I-1J-5051D01*
G01D02*
X848888Y1466402D01*
G01X878937Y1440473D02*
X873730D01*
G01D02*
G02X873213Y1440687I0J732D01*
G01D02*
G02X872999Y1441204I518J517D01*
G01D02*
Y1441710D01*
G01D02*
G03X872636Y1442259I-599J-2D01*
G01D02*
G03X872634Y1442261I-394J-392D01*
G01D02*
G03X872399Y1442310I-237J-551D01*
G01D02*
X863999D01*
G01D02*
G03X860742Y1440961I0J-4606D01*
G01D02*
X860577Y1440796D01*
G01X878937Y1445473D02*
X873513D01*
G01D02*
G03X873150Y1445323I0J-514D01*
G01D02*
G03X872999Y1444958I366J-365D01*
G01D02*
Y1444210D01*
G01D02*
G02X872399Y1443610I-600J0D01*
G01D02*
X862999D01*
G01D02*
G02X860577Y1444296I0J4619D01*
G01X887401Y1466103D02*
X883523D01*
G01D02*
X883510Y1466090D01*
G01D02*
G02X882752Y1466404I0J1072D01*
G01D02*
G03X881279Y1467014I-1473J-1473D01*
G01D02*
X863399D01*
G01D02*
G03X860661Y1465880I0J-3872D01*
G01D02*
X860577Y1465796D01*
G01X887401Y1469252D02*
X883828D01*
G01D02*
X883815Y1469239D01*
G01D02*
G03X882538Y1468710I0J-1806D01*
G01D02*
G02X881582Y1468314I-956J956D01*
G01D02*
X862899D01*
G01D02*
G02X860612Y1469262I1J3235D01*
G01D02*
X860577Y1469296D01*
G01X878937Y1430473D02*
X873630D01*
G01D02*
G03X872999Y1429842I0J-631D01*
G01D02*
Y1429210D01*
G01D02*
G02X872399Y1428610I-600J0D01*
G01D02*
X849999D01*
G01D02*
G02X847583Y1428996I0J7754D01*
G01X878937Y1425473D02*
X873618D01*
G01D02*
G02X872999Y1426092I0J619D01*
G01D02*
Y1426710D01*
G01D02*
G03X872399Y1427310I-600J0D01*
G01D02*
X849999D01*
G01D02*
G02X847257Y1427733I0J9099D01*
G01X887401Y1459803D02*
X883612D01*
G01D02*
X883599Y1459790D01*
G01D02*
G03X882689Y1459413I0J-1287D01*
G01D02*
X882412Y1459136D01*
G01D02*
G02X881760Y1458866I-652J652D01*
G01D02*
X878978D01*
G01D02*
G02X877853Y1459991I0J1125D01*
G01X887401Y1456654D02*
X883489D01*
G01D02*
X883476Y1456641D01*
G01D02*
G02X882778Y1456930I0J987D01*
G01D02*
G03X881243Y1457566I-1535J-1535D01*
G01D02*
X879170D01*
G01D02*
G03X878054Y1456450I0J-1116D01*
G01X840519Y1844080D02*
X840520D01*
G01D02*
X842248Y1845808D01*
G01D02*
G02X849501Y1848813I7253J-7251D01*
G01D02*
X854499D01*
G01D02*
G02X858537Y1847141I1J-5710D01*
G01D02*
X859064Y1846613D01*
G01X841328Y1846728D02*
G02X849500Y1850113I8172J-8172D01*
G01D02*
X859064D01*
G01Y1871113D02*
X857999D01*
G01D02*
G02X856688Y1871656I0J1854D01*
G01D02*
X856396Y1871948D01*
G01D02*
G03X855756Y1872213I-640J-640D01*
G01D02*
X854676D01*
G01D02*
G03X853499Y1871036I0J-1177D01*
G01X859064Y1874613D02*
X857743D01*
G01D02*
G03X856869Y1874251I0J-1236D01*
G01D02*
X856578Y1873960D01*
G01D02*
G02X855499Y1873513I-1079J1079D01*
G01D02*
X853999D01*
G01D02*
G03X851535Y1872493I-1J-3484D01*
G01D02*
X850099Y1871056D01*
G01X878937Y1845985D02*
X873478D01*
G01D02*
G02X873200Y1846100I0J393D01*
G01D02*
G02X872900Y1846824I724J724D01*
G01D02*
Y1847200D01*
G01D02*
G03X872278Y1847822I-622J0D01*
G01D02*
X865483D01*
G01D02*
G03X862564Y1846613I0J-4128D01*
G01X878937Y1850985D02*
X874013D01*
G01D02*
G03X873650Y1850834I1J-514D01*
G01D02*
X873610Y1850794D01*
G01D02*
G03X873499Y1850528I263J-266D01*
G01D02*
Y1850047D01*
G01D02*
G02X872756Y1849140I-925J0D01*
G01D02*
G02X872574Y1849122I-182J907D01*
G01D02*
X864956D01*
G01D02*
G02X862564Y1850113I0J3383D01*
G01X887401Y1871615D02*
X887388Y1871602D01*
G01D02*
X883572D01*
G01D02*
G02X882708Y1871960I0J1222D01*
G01D02*
X882408Y1872260D01*
G01D02*
G03X881766Y1872526I-642J-642D01*
G01D02*
X865975D01*
G01D02*
G03X862564Y1871113I0J-4824D01*
G01X887401Y1874764D02*
X887388Y1874751D01*
G01D02*
X883682D01*
G01D02*
G03X882632Y1874316I0J-1485D01*
G01D02*
X882432Y1874116D01*
G01D02*
G02X881732Y1873826I-700J700D01*
G01D02*
X863351D01*
G01D02*
G02X862564Y1874613I0J787D01*
G01X878937Y1835985D02*
X872716D01*
G01D02*
G03X871999Y1835268I0J-717D01*
G01D02*
Y1834550D01*
G01D02*
G02X871582Y1834133I-417J0D01*
G01X878937Y1830985D02*
X873064D01*
G01D02*
G02X871999Y1832050I0J1065D01*
G01D02*
G03X871670Y1832687I-781J0D01*
G01D02*
G03X871321Y1832825I-454J-637D01*
G01D02*
G03X871216Y1832833I-112J-774D01*
G01X887401Y1865315D02*
X887388Y1865302D01*
G01D02*
X883399D01*
G01D02*
G03X882757Y1864992I0J-820D01*
G01D02*
X882457Y1864692D01*
G01D02*
G02X882406Y1864669I-1477J3208D01*
G01D02*
G02X880999Y1864377I-1406J3240D01*
G01D02*
X869099D01*
G01D02*
G02X866914Y1865615I0J2547D01*
G01X887401Y1862166D02*
X887388Y1862153D01*
G01D02*
X883499D01*
G01D02*
G02X882684Y1862535I0J1060D01*
G01D02*
G03X882226Y1862803I-1682J-2350D01*
G01D02*
G03X880999Y1863077I-1228J-2616D01*
G01D02*
X868151D01*
G01D02*
G03X866914Y1861840I0J-1237D01*
M02*
